FILE_TYPE = MACRO_DRAWING;
SET COLOR_WIRE YELLOW;
SET COLOR_PROP ORANGE;
SET COLOR_DOT WHITE;
SET COLOR_ARC YELLOW;
SET COLOR_BODY GREEN;
SET COLOR_NOTE PURPLE;
SET PROP_DISPLAY VALUE;
SET PAGE_NUMBER P50;
FORCEADD GENOA_SP5..13
(-4750 5050);
FORCEPROP 1 LAST LOCATION U26
J 0
(-5845 6306);
DISPLAY 0.489362 (-5845 6306);
PAINT SKYBLUE (-5845 6306);
FORCEPROP 0 LAST $SEC 13
J 0
(-5825 6350);
DISPLAY 0.680851 (-5825 6350);
PAINT MONO (-5825 6350);
DISPLAY INVISIBLE (-5825 6350);
FORCEPROP 0 LAST CDS_SEC 13
J 0
(-5850 6275);
DISPLAY 1.021277 (-5850 6275);
DISPLAY INVISIBLE (-5850 6275);
FORCEPROP 0 LASTPIN (-6000 5750) $PN AE23
J 2
(-6010 5760);
DISPLAY 0.489362 (-6010 5760);
PAINT MONO (-6010 5760);
FORCEPROP 0 LASTPIN (-6000 5650) $PN AC23
J 2
(-6010 5660);
DISPLAY 0.489362 (-6010 5660);
PAINT MONO (-6010 5660);
FORCEPROP 0 LASTPIN (-6000 5550) $PN AG23
J 2
(-6010 5560);
DISPLAY 0.489362 (-6010 5560);
PAINT MONO (-6010 5560);
FORCEPROP 0 LASTPIN (-6000 5450) $PN AE26
J 2
(-6010 5460);
DISPLAY 0.489362 (-6010 5460);
PAINT MONO (-6010 5460);
FORCEPROP 0 LASTPIN (-6000 5350) $PN AC26
J 2
(-6010 5360);
DISPLAY 0.489362 (-6010 5360);
PAINT MONO (-6010 5360);
FORCEPROP 0 LASTPIN (-6000 5250) $PN AG26
J 2
(-6010 5260);
DISPLAY 0.489362 (-6010 5260);
PAINT MONO (-6010 5260);
FORCEPROP 0 LASTPIN (-6000 5150) $PN AE29
J 2
(-6010 5160);
DISPLAY 0.489362 (-6010 5160);
PAINT MONO (-6010 5160);
FORCEPROP 0 LASTPIN (-6000 5050) $PN AC29
J 2
(-6010 5060);
DISPLAY 0.489362 (-6010 5060);
PAINT MONO (-6010 5060);
FORCEPROP 0 LASTPIN (-6000 4950) $PN AG29
J 2
(-6010 4960);
DISPLAY 0.489362 (-6010 4960);
PAINT MONO (-6010 4960);
FORCEPROP 0 LASTPIN (-6000 4850) $PN AE32
J 2
(-6010 4860);
DISPLAY 0.489362 (-6010 4860);
PAINT MONO (-6010 4860);
FORCEPROP 0 LASTPIN (-6000 4750) $PN AC32
J 2
(-6010 4760);
DISPLAY 0.489362 (-6010 4760);
PAINT MONO (-6010 4760);
FORCEPROP 0 LASTPIN (-6000 4650) $PN AA32
J 2
(-6010 4660);
DISPLAY 0.489362 (-6010 4660);
PAINT MONO (-6010 4660);
FORCEPROP 0 LASTPIN (-6000 4550) $PN AG32
J 2
(-6010 4560);
DISPLAY 0.489362 (-6010 4560);
PAINT MONO (-6010 4560);
FORCEPROP 0 LASTPIN (-6000 4450) $PN AB35
J 2
(-6010 4460);
DISPLAY 0.489362 (-6010 4460);
PAINT MONO (-6010 4460);
FORCEPROP 0 LASTPIN (-6000 4350) $PN AD35
J 2
(-6010 4360);
DISPLAY 0.489362 (-6010 4360);
PAINT MONO (-6010 4360);
FORCEPROP 0 LASTPIN (-6000 4250) $PN AF35
J 2
(-6010 4260);
DISPLAY 0.489362 (-6010 4260);
PAINT MONO (-6010 4260);
FORCEPROP 0 LASTPIN (-6000 5800) $PN AE24
J 2
(-6010 5810);
DISPLAY 0.489362 (-6010 5810);
PAINT MONO (-6010 5810);
FORCEPROP 0 LASTPIN (-6000 5700) $PN AC24
J 2
(-6010 5710);
DISPLAY 0.489362 (-6010 5710);
PAINT MONO (-6010 5710);
FORCEPROP 0 LASTPIN (-6000 5600) $PN AG24
J 2
(-6010 5610);
DISPLAY 0.489362 (-6010 5610);
PAINT MONO (-6010 5610);
FORCEPROP 0 LASTPIN (-6000 5500) $PN AE27
J 2
(-6010 5510);
DISPLAY 0.489362 (-6010 5510);
PAINT MONO (-6010 5510);
FORCEPROP 0 LASTPIN (-6000 5400) $PN AC27
J 2
(-6010 5410);
DISPLAY 0.489362 (-6010 5410);
PAINT MONO (-6010 5410);
FORCEPROP 0 LASTPIN (-6000 5300) $PN AG27
J 2
(-6010 5310);
DISPLAY 0.489362 (-6010 5310);
PAINT MONO (-6010 5310);
FORCEPROP 0 LASTPIN (-6000 5200) $PN AE30
J 2
(-6010 5210);
DISPLAY 0.489362 (-6010 5210);
PAINT MONO (-6010 5210);
FORCEPROP 0 LASTPIN (-6000 5100) $PN AC30
J 2
(-6010 5110);
DISPLAY 0.489362 (-6010 5110);
PAINT MONO (-6010 5110);
FORCEPROP 0 LASTPIN (-6000 5000) $PN AG30
J 2
(-6010 5010);
DISPLAY 0.489362 (-6010 5010);
PAINT MONO (-6010 5010);
FORCEPROP 0 LASTPIN (-6000 4900) $PN AE33
J 2
(-6010 4910);
DISPLAY 0.489362 (-6010 4910);
PAINT MONO (-6010 4910);
FORCEPROP 0 LASTPIN (-6000 4800) $PN AC33
J 2
(-6010 4810);
DISPLAY 0.489362 (-6010 4810);
PAINT MONO (-6010 4810);
FORCEPROP 0 LASTPIN (-6000 4700) $PN AA33
J 2
(-6010 4710);
DISPLAY 0.489362 (-6010 4710);
PAINT MONO (-6010 4710);
FORCEPROP 0 LASTPIN (-6000 4600) $PN AG33
J 2
(-6010 4610);
DISPLAY 0.489362 (-6010 4610);
PAINT MONO (-6010 4610);
FORCEPROP 0 LASTPIN (-6000 4500) $PN AB36
J 2
(-6010 4510);
DISPLAY 0.489362 (-6010 4510);
PAINT MONO (-6010 4510);
FORCEPROP 0 LASTPIN (-6000 4400) $PN AD36
J 2
(-6010 4410);
DISPLAY 0.489362 (-6010 4410);
PAINT MONO (-6010 4410);
FORCEPROP 0 LASTPIN (-6000 4300) $PN AF36
J 2
(-6010 4310);
DISPLAY 0.489362 (-6010 4310);
PAINT MONO (-6010 4310);
FORCEPROP 0 LASTPIN (-3500 5750) $PN N24
J 0
(-3490 5760);
DISPLAY 0.489362 (-3490 5760);
PAINT MONO (-3490 5760);
FORCEPROP 0 LASTPIN (-3500 5650) $PN J24
J 0
(-3490 5660);
DISPLAY 0.489362 (-3490 5660);
PAINT MONO (-3490 5660);
FORCEPROP 0 LASTPIN (-3500 5550) $PN G24
J 0
(-3490 5560);
DISPLAY 0.489362 (-3490 5560);
PAINT MONO (-3490 5560);
FORCEPROP 0 LASTPIN (-3500 5450) $PN L24
J 0
(-3490 5460);
DISPLAY 0.489362 (-3490 5460);
PAINT MONO (-3490 5460);
FORCEPROP 0 LASTPIN (-3500 5350) $PN J27
J 0
(-3490 5360);
DISPLAY 0.489362 (-3490 5360);
PAINT MONO (-3490 5360);
FORCEPROP 0 LASTPIN (-3500 5250) $PN G27
J 0
(-3490 5260);
DISPLAY 0.489362 (-3490 5260);
PAINT MONO (-3490 5260);
FORCEPROP 0 LASTPIN (-3500 5150) $PN L27
J 0
(-3490 5160);
DISPLAY 0.489362 (-3490 5160);
PAINT MONO (-3490 5160);
FORCEPROP 0 LASTPIN (-3500 5050) $PN J30
J 0
(-3490 5060);
DISPLAY 0.489362 (-3490 5060);
PAINT MONO (-3490 5060);
FORCEPROP 0 LASTPIN (-3500 4950) $PN G30
J 0
(-3490 4960);
DISPLAY 0.489362 (-3490 4960);
PAINT MONO (-3490 4960);
FORCEPROP 0 LASTPIN (-3500 4850) $PN L30
J 0
(-3490 4860);
DISPLAY 0.489362 (-3490 4860);
PAINT MONO (-3490 4860);
FORCEPROP 0 LASTPIN (-3500 4750) $PN J33
J 0
(-3490 4760);
DISPLAY 0.489362 (-3490 4760);
PAINT MONO (-3490 4760);
FORCEPROP 0 LASTPIN (-3500 4650) $PN G33
J 0
(-3490 4660);
DISPLAY 0.489362 (-3490 4660);
PAINT MONO (-3490 4660);
FORCEPROP 0 LASTPIN (-3500 4550) $PN L33
J 0
(-3490 4560);
DISPLAY 0.489362 (-3490 4560);
PAINT MONO (-3490 4560);
FORCEPROP 0 LASTPIN (-3500 4450) $PN H36
J 0
(-3490 4460);
DISPLAY 0.489362 (-3490 4460);
PAINT MONO (-3490 4460);
FORCEPROP 0 LASTPIN (-3500 4350) $PN K36
J 0
(-3490 4360);
DISPLAY 0.489362 (-3490 4360);
PAINT MONO (-3490 4360);
FORCEPROP 0 LASTPIN (-3500 4250) $PN M36
J 0
(-3490 4260);
DISPLAY 0.489362 (-3490 4260);
PAINT MONO (-3490 4260);
FORCEPROP 0 LASTPIN (-3500 5800) $PN N23
J 0
(-3490 5810);
DISPLAY 0.489362 (-3490 5810);
PAINT MONO (-3490 5810);
FORCEPROP 0 LASTPIN (-3500 5700) $PN J23
J 0
(-3490 5710);
DISPLAY 0.489362 (-3490 5710);
PAINT MONO (-3490 5710);
FORCEPROP 0 LASTPIN (-3500 5600) $PN G23
J 0
(-3490 5610);
DISPLAY 0.489362 (-3490 5610);
PAINT MONO (-3490 5610);
FORCEPROP 0 LASTPIN (-3500 5500) $PN L23
J 0
(-3490 5510);
DISPLAY 0.489362 (-3490 5510);
PAINT MONO (-3490 5510);
FORCEPROP 0 LASTPIN (-3500 5400) $PN J26
J 0
(-3490 5410);
DISPLAY 0.489362 (-3490 5410);
PAINT MONO (-3490 5410);
FORCEPROP 0 LASTPIN (-3500 5300) $PN G26
J 0
(-3490 5310);
DISPLAY 0.489362 (-3490 5310);
PAINT MONO (-3490 5310);
FORCEPROP 0 LASTPIN (-3500 5200) $PN L26
J 0
(-3490 5210);
DISPLAY 0.489362 (-3490 5210);
PAINT MONO (-3490 5210);
FORCEPROP 0 LASTPIN (-3500 5100) $PN J29
J 0
(-3490 5110);
DISPLAY 0.489362 (-3490 5110);
PAINT MONO (-3490 5110);
FORCEPROP 0 LASTPIN (-3500 5000) $PN G29
J 0
(-3490 5010);
DISPLAY 0.489362 (-3490 5010);
PAINT MONO (-3490 5010);
FORCEPROP 0 LASTPIN (-3500 4900) $PN L29
J 0
(-3490 4910);
DISPLAY 0.489362 (-3490 4910);
PAINT MONO (-3490 4910);
FORCEPROP 0 LASTPIN (-3500 4800) $PN J32
J 0
(-3490 4810);
DISPLAY 0.489362 (-3490 4810);
PAINT MONO (-3490 4810);
FORCEPROP 0 LASTPIN (-3500 4700) $PN G32
J 0
(-3490 4710);
DISPLAY 0.489362 (-3490 4710);
PAINT MONO (-3490 4710);
FORCEPROP 0 LASTPIN (-3500 4600) $PN L32
J 0
(-3490 4610);
DISPLAY 0.489362 (-3490 4610);
PAINT MONO (-3490 4610);
FORCEPROP 0 LASTPIN (-3500 4500) $PN H35
J 0
(-3490 4510);
DISPLAY 0.489362 (-3490 4510);
PAINT MONO (-3490 4510);
FORCEPROP 0 LASTPIN (-3500 4400) $PN K35
J 0
(-3490 4410);
DISPLAY 0.489362 (-3490 4410);
PAINT MONO (-3490 4410);
FORCEPROP 0 LASTPIN (-3500 4300) $PN M35
J 0
(-3490 4310);
DISPLAY 0.489362 (-3490 4310);
PAINT MONO (-3490 4310);
FORCEPROP 2 LAST PART_TYPE SMLF
J 0
(-5850 6225);
DISPLAY 1.021277 (-5850 6225);
FORCEPROP 1 LAST MATERIAL IO
J 0
(-5845 6032);
DISPLAY 0.489362 (-5845 6032);
PAINT SKYBLUE (-5845 6032);
FORCEPROP 2 LAST VALUE SOCKET6096_13568-001
J 0
(-5850 6125);
DISPLAY 0.489362 (-5850 6125);
PAINT SKYBLUE (-5850 6125);
FORCEPROP 1 LAST PART_NUMBER DGA^6000030
J 0
(-5845 6159);
DISPLAY 0.489362 (-5845 6159);
PAINT SKYBLUE (-5845 6159);
FORCEPROP 2 LAST CDS_LIB pure_quanta
J 0
(-4750 5050);
DISPLAY INVISIBLE (-4750 5050);
FORCEPROP 1 LAST NEEDS_NO_SIZE TRUE
J 0
(-4750 5050);
DISPLAY 0.723404 (-4750 5050);
PAINT GREEN (-4750 5050);
DISPLAY INVISIBLE (-4750 5050);
FORCEPROP 1 LAST CDS_LMAN_SYM_OUTLINE -1100,950,1100,-950
J 0
(-4750 5050);
DISPLAY 0.468085 (-4750 5050);
PAINT GREEN (-4750 5050);
DISPLAY INVISIBLE (-4750 5050);
FORCEPROP 1 LAST PATH I143
J 0
(-4750 5050);
DISPLAY 0.723404 (-4750 5050);
PAINT GREEN (-4750 5050);
DISPLAY INVISIBLE (-4750 5050);
FORCEADD GENOA_SP5..14
(-4725 2375);
FORCEPROP 1 LAST LOCATION U26
J 0
(-5820 3631);
DISPLAY 0.489362 (-5820 3631);
PAINT SKYBLUE (-5820 3631);
FORCEPROP 0 LAST $SEC 14
J 0
(-5800 3675);
DISPLAY 0.680851 (-5800 3675);
PAINT MONO (-5800 3675);
DISPLAY INVISIBLE (-5800 3675);
FORCEPROP 0 LAST CDS_SEC 14
J 0
(-5825 3600);
DISPLAY 1.021277 (-5825 3600);
DISPLAY INVISIBLE (-5825 3600);
FORCEPROP 0 LASTPIN (-5975 3075) $PN AL23
J 2
(-5985 3085);
DISPLAY 0.489362 (-5985 3085);
PAINT MONO (-5985 3085);
FORCEPROP 0 LASTPIN (-5975 2975) $PN AJ23
J 2
(-5985 2985);
DISPLAY 0.489362 (-5985 2985);
PAINT MONO (-5985 2985);
FORCEPROP 0 LASTPIN (-5975 2875) $PN AN23
J 2
(-5985 2885);
DISPLAY 0.489362 (-5985 2885);
PAINT MONO (-5985 2885);
FORCEPROP 0 LASTPIN (-5975 2775) $PN AL26
J 2
(-5985 2785);
DISPLAY 0.489362 (-5985 2785);
PAINT MONO (-5985 2785);
FORCEPROP 0 LASTPIN (-5975 2675) $PN AJ26
J 2
(-5985 2685);
DISPLAY 0.489362 (-5985 2685);
PAINT MONO (-5985 2685);
FORCEPROP 0 LASTPIN (-5975 2575) $PN AN26
J 2
(-5985 2585);
DISPLAY 0.489362 (-5985 2585);
PAINT MONO (-5985 2585);
FORCEPROP 0 LASTPIN (-5975 2475) $PN AL29
J 2
(-5985 2485);
DISPLAY 0.489362 (-5985 2485);
PAINT MONO (-5985 2485);
FORCEPROP 0 LASTPIN (-5975 2375) $PN AJ29
J 2
(-5985 2385);
DISPLAY 0.489362 (-5985 2385);
PAINT MONO (-5985 2385);
FORCEPROP 0 LASTPIN (-5975 2275) $PN AN29
J 2
(-5985 2285);
DISPLAY 0.489362 (-5985 2285);
PAINT MONO (-5985 2285);
FORCEPROP 0 LASTPIN (-5975 2175) $PN AL32
J 2
(-5985 2185);
DISPLAY 0.489362 (-5985 2185);
PAINT MONO (-5985 2185);
FORCEPROP 0 LASTPIN (-5975 2075) $PN AJ32
J 2
(-5985 2085);
DISPLAY 0.489362 (-5985 2085);
PAINT MONO (-5985 2085);
FORCEPROP 0 LASTPIN (-5975 1975) $PN AN32
J 2
(-5985 1985);
DISPLAY 0.489362 (-5985 1985);
PAINT MONO (-5985 1985);
FORCEPROP 0 LASTPIN (-5975 1875) $PN AK35
J 2
(-5985 1885);
DISPLAY 0.489362 (-5985 1885);
PAINT MONO (-5985 1885);
FORCEPROP 0 LASTPIN (-5975 1775) $PN AH35
J 2
(-5985 1785);
DISPLAY 0.489362 (-5985 1785);
PAINT MONO (-5985 1785);
FORCEPROP 0 LASTPIN (-5975 1675) $PN AM35
J 2
(-5985 1685);
DISPLAY 0.489362 (-5985 1685);
PAINT MONO (-5985 1685);
FORCEPROP 0 LASTPIN (-5975 1575) $PN AP35
J 2
(-5985 1585);
DISPLAY 0.489362 (-5985 1585);
PAINT MONO (-5985 1585);
FORCEPROP 0 LASTPIN (-5975 3125) $PN AL24
J 2
(-5985 3135);
DISPLAY 0.489362 (-5985 3135);
PAINT MONO (-5985 3135);
FORCEPROP 0 LASTPIN (-5975 3025) $PN AJ24
J 2
(-5985 3035);
DISPLAY 0.489362 (-5985 3035);
PAINT MONO (-5985 3035);
FORCEPROP 0 LASTPIN (-5975 2925) $PN AN24
J 2
(-5985 2935);
DISPLAY 0.489362 (-5985 2935);
PAINT MONO (-5985 2935);
FORCEPROP 0 LASTPIN (-5975 2825) $PN AL27
J 2
(-5985 2835);
DISPLAY 0.489362 (-5985 2835);
PAINT MONO (-5985 2835);
FORCEPROP 0 LASTPIN (-5975 2725) $PN AJ27
J 2
(-5985 2735);
DISPLAY 0.489362 (-5985 2735);
PAINT MONO (-5985 2735);
FORCEPROP 0 LASTPIN (-5975 2625) $PN AN27
J 2
(-5985 2635);
DISPLAY 0.489362 (-5985 2635);
PAINT MONO (-5985 2635);
FORCEPROP 0 LASTPIN (-5975 2525) $PN AL30
J 2
(-5985 2535);
DISPLAY 0.489362 (-5985 2535);
PAINT MONO (-5985 2535);
FORCEPROP 0 LASTPIN (-5975 2425) $PN AJ30
J 2
(-5985 2435);
DISPLAY 0.489362 (-5985 2435);
PAINT MONO (-5985 2435);
FORCEPROP 0 LASTPIN (-5975 2325) $PN AN30
J 2
(-5985 2335);
DISPLAY 0.489362 (-5985 2335);
PAINT MONO (-5985 2335);
FORCEPROP 0 LASTPIN (-5975 2225) $PN AL33
J 2
(-5985 2235);
DISPLAY 0.489362 (-5985 2235);
PAINT MONO (-5985 2235);
FORCEPROP 0 LASTPIN (-5975 2125) $PN AJ33
J 2
(-5985 2135);
DISPLAY 0.489362 (-5985 2135);
PAINT MONO (-5985 2135);
FORCEPROP 0 LASTPIN (-5975 2025) $PN AN33
J 2
(-5985 2035);
DISPLAY 0.489362 (-5985 2035);
PAINT MONO (-5985 2035);
FORCEPROP 0 LASTPIN (-5975 1925) $PN AK36
J 2
(-5985 1935);
DISPLAY 0.489362 (-5985 1935);
PAINT MONO (-5985 1935);
FORCEPROP 0 LASTPIN (-5975 1825) $PN AH36
J 2
(-5985 1835);
DISPLAY 0.489362 (-5985 1835);
PAINT MONO (-5985 1835);
FORCEPROP 0 LASTPIN (-5975 1725) $PN AM36
J 2
(-5985 1735);
DISPLAY 0.489362 (-5985 1735);
PAINT MONO (-5985 1735);
FORCEPROP 0 LASTPIN (-5975 1625) $PN AP36
J 2
(-5985 1635);
DISPLAY 0.489362 (-5985 1635);
PAINT MONO (-5985 1635);
FORCEPROP 0 LASTPIN (-3475 3075) $PN U24
J 0
(-3465 3085);
DISPLAY 0.489362 (-3465 3085);
PAINT MONO (-3465 3085);
FORCEPROP 0 LASTPIN (-3475 2975) $PN R24
J 0
(-3465 2985);
DISPLAY 0.489362 (-3465 2985);
PAINT MONO (-3465 2985);
FORCEPROP 0 LASTPIN (-3475 2875) $PN W24
J 0
(-3465 2885);
DISPLAY 0.489362 (-3465 2885);
PAINT MONO (-3465 2885);
FORCEPROP 0 LASTPIN (-3475 2775) $PN U27
J 0
(-3465 2785);
DISPLAY 0.489362 (-3465 2785);
PAINT MONO (-3465 2785);
FORCEPROP 0 LASTPIN (-3475 2675) $PN R27
J 0
(-3465 2685);
DISPLAY 0.489362 (-3465 2685);
PAINT MONO (-3465 2685);
FORCEPROP 0 LASTPIN (-3475 2575) $PN N27
J 0
(-3465 2585);
DISPLAY 0.489362 (-3465 2585);
PAINT MONO (-3465 2585);
FORCEPROP 0 LASTPIN (-3475 2475) $PN W27
J 0
(-3465 2485);
DISPLAY 0.489362 (-3465 2485);
PAINT MONO (-3465 2485);
FORCEPROP 0 LASTPIN (-3475 2375) $PN R30
J 0
(-3465 2385);
DISPLAY 0.489362 (-3465 2385);
PAINT MONO (-3465 2385);
FORCEPROP 0 LASTPIN (-3475 2275) $PN N30
J 0
(-3465 2285);
DISPLAY 0.489362 (-3465 2285);
PAINT MONO (-3465 2285);
FORCEPROP 0 LASTPIN (-3475 2175) $PN U30
J 0
(-3465 2185);
DISPLAY 0.489362 (-3465 2185);
PAINT MONO (-3465 2185);
FORCEPROP 0 LASTPIN (-3475 2075) $PN R33
J 0
(-3465 2085);
DISPLAY 0.489362 (-3465 2085);
PAINT MONO (-3465 2085);
FORCEPROP 0 LASTPIN (-3475 1975) $PN N33
J 0
(-3465 1985);
DISPLAY 0.489362 (-3465 1985);
PAINT MONO (-3465 1985);
FORCEPROP 0 LASTPIN (-3475 1875) $PN U33
J 0
(-3465 1885);
DISPLAY 0.489362 (-3465 1885);
PAINT MONO (-3465 1885);
FORCEPROP 0 LASTPIN (-3475 1775) $PN P36
J 0
(-3465 1785);
DISPLAY 0.489362 (-3465 1785);
PAINT MONO (-3465 1785);
FORCEPROP 0 LASTPIN (-3475 1675) $PN T36
J 0
(-3465 1685);
DISPLAY 0.489362 (-3465 1685);
PAINT MONO (-3465 1685);
FORCEPROP 0 LASTPIN (-3475 1575) $PN V36
J 0
(-3465 1585);
DISPLAY 0.489362 (-3465 1585);
PAINT MONO (-3465 1585);
FORCEPROP 0 LASTPIN (-3475 3125) $PN U23
J 0
(-3465 3135);
DISPLAY 0.489362 (-3465 3135);
PAINT MONO (-3465 3135);
FORCEPROP 0 LASTPIN (-3475 3025) $PN R23
J 0
(-3465 3035);
DISPLAY 0.489362 (-3465 3035);
PAINT MONO (-3465 3035);
FORCEPROP 0 LASTPIN (-3475 2925) $PN W23
J 0
(-3465 2935);
DISPLAY 0.489362 (-3465 2935);
PAINT MONO (-3465 2935);
FORCEPROP 0 LASTPIN (-3475 2825) $PN U26
J 0
(-3465 2835);
DISPLAY 0.489362 (-3465 2835);
PAINT MONO (-3465 2835);
FORCEPROP 0 LASTPIN (-3475 2725) $PN R26
J 0
(-3465 2735);
DISPLAY 0.489362 (-3465 2735);
PAINT MONO (-3465 2735);
FORCEPROP 0 LASTPIN (-3475 2625) $PN N26
J 0
(-3465 2635);
DISPLAY 0.489362 (-3465 2635);
PAINT MONO (-3465 2635);
FORCEPROP 0 LASTPIN (-3475 2525) $PN W26
J 0
(-3465 2535);
DISPLAY 0.489362 (-3465 2535);
PAINT MONO (-3465 2535);
FORCEPROP 0 LASTPIN (-3475 2425) $PN R29
J 0
(-3465 2435);
DISPLAY 0.489362 (-3465 2435);
PAINT MONO (-3465 2435);
FORCEPROP 0 LASTPIN (-3475 2325) $PN N29
J 0
(-3465 2335);
DISPLAY 0.489362 (-3465 2335);
PAINT MONO (-3465 2335);
FORCEPROP 0 LASTPIN (-3475 2225) $PN U29
J 0
(-3465 2235);
DISPLAY 0.489362 (-3465 2235);
PAINT MONO (-3465 2235);
FORCEPROP 0 LASTPIN (-3475 2125) $PN R32
J 0
(-3465 2135);
DISPLAY 0.489362 (-3465 2135);
PAINT MONO (-3465 2135);
FORCEPROP 0 LASTPIN (-3475 2025) $PN N32
J 0
(-3465 2035);
DISPLAY 0.489362 (-3465 2035);
PAINT MONO (-3465 2035);
FORCEPROP 0 LASTPIN (-3475 1925) $PN U32
J 0
(-3465 1935);
DISPLAY 0.489362 (-3465 1935);
PAINT MONO (-3465 1935);
FORCEPROP 0 LASTPIN (-3475 1825) $PN P35
J 0
(-3465 1835);
DISPLAY 0.489362 (-3465 1835);
PAINT MONO (-3465 1835);
FORCEPROP 0 LASTPIN (-3475 1725) $PN T35
J 0
(-3465 1735);
DISPLAY 0.489362 (-3465 1735);
PAINT MONO (-3465 1735);
FORCEPROP 0 LASTPIN (-3475 1625) $PN V35
J 0
(-3465 1635);
DISPLAY 0.489362 (-3465 1635);
PAINT MONO (-3465 1635);
FORCEPROP 2 LAST PART_TYPE SMLF
J 0
(-5825 3550);
DISPLAY 1.021277 (-5825 3550);
FORCEPROP 1 LAST MATERIAL IO
J 0
(-5820 3357);
DISPLAY 0.489362 (-5820 3357);
PAINT SKYBLUE (-5820 3357);
FORCEPROP 2 LAST VALUE SOCKET6096_13568-001
J 0
(-5825 3450);
DISPLAY 0.489362 (-5825 3450);
PAINT SKYBLUE (-5825 3450);
FORCEPROP 1 LAST PART_NUMBER DGA^6000030
J 0
(-5820 3484);
DISPLAY 0.489362 (-5820 3484);
PAINT SKYBLUE (-5820 3484);
FORCEPROP 2 LAST CDS_LIB pure_quanta
J 0
(-4725 2375);
DISPLAY INVISIBLE (-4725 2375);
FORCEPROP 1 LAST NEEDS_NO_SIZE TRUE
J 0
(-4725 2375);
DISPLAY 0.723404 (-4725 2375);
PAINT GREEN (-4725 2375);
DISPLAY INVISIBLE (-4725 2375);
FORCEPROP 1 LAST CDS_LMAN_SYM_OUTLINE -1100,950,1100,-950
J 0
(-4725 2375);
DISPLAY 0.468085 (-4725 2375);
PAINT GREEN (-4725 2375);
DISPLAY INVISIBLE (-4725 2375);
FORCEPROP 1 LAST PATH I144
J 0
(-4725 2375);
DISPLAY 0.723404 (-4725 2375);
PAINT GREEN (-4725 2375);
DISPLAY INVISIBLE (-4725 2375);
FORCEADD OFFPAGE..2
(-1800 6025);
FORCEPROP 2 LAST $XR0 22 
J 0
(-1611 6025);
DISPLAY 0.638298 (-1611 6025);
PAINT MONO (-1611 6025);
FORCEPROP 2 LAST PATH I195
J 0
(-1600 6075);
DISPLAY 1.021277 (-1600 6075);
DISPLAY INVISIBLE (-1600 6075);
FORCEPROP 1 LAST COMMENT_BODY TRUE
J 0
(-1845 5930);
DISPLAY 0.872340 (-1845 5930);
PAINT GREEN (-1845 5930);
DISPLAY INVISIBLE (-1845 5930);
FORCEPROP 1 LAST OFFPAGE TRUE
J 0
(-1475 5900);
DISPLAY 0.872340 (-1475 5900);
PAINT GREEN (-1475 5900);
DISPLAY INVISIBLE (-1475 5900);
FORCEPROP 2 LAST CDS_LIB standard
J 0
(-1800 6025);
DISPLAY INVISIBLE (-1800 6025);
FORCEADD TAP..6
R 2
(-3075 5800);
FORCEPROP 3 LASTPIN (-3125 5800) SIG_NAME GMI_CPU1_G2_CPU0_G0_TX_DP<15>
J 0
(-3115 5810);
DISPLAY 0.659574 (-3115 5810);
PAINT MONO (-3115 5810);
DISPLAY INVISIBLE (-3115 5810);
FORCEPROP 1 LASTPIN (-3125 5800) BN 15
J 2
(-3073 5808);
DISPLAY 0.489362 (-3073 5808);
PAINT MONO (-3073 5808);
FORCEPROP 2 LAST BOM_COST IO_SLOT
J 0
(-3575 5900);
DISPLAY 0.829787 (-3575 5900);
DISPLAY INVISIBLE (-3575 5900);
FORCEPROP 2 LAST CDS_LIB mstr_standard
J 0
(-3075 5800);
DISPLAY INVISIBLE (-3075 5800);
FORCEPROP 1 LAST BODY_TYPE PLUMBING
J 2
(-3075 5750);
DISPLAY 0.702128 (-3075 5750);
PAINT GREEN (-3075 5750);
DISPLAY INVISIBLE (-3075 5750);
FORCEPROP 1 LAST HDL_TAP TRUE
J 2
(-3400 5675);
DISPLAY 0.702128 (-3400 5675);
PAINT GREEN (-3400 5675);
DISPLAY INVISIBLE (-3400 5675);
FORCEPROP 1 LAST PATH I198
J 2
(-3073 5800);
DISPLAY 0.872340 (-3073 5800);
PAINT GREEN (-3073 5800);
DISPLAY INVISIBLE (-3073 5800);
FORCEPROP 2 LAST ROOM RISER1
J 0
(-3575 5850);
DISPLAY 0.829787 (-3575 5850);
PAINT RED (-3575 5850);
DISPLAY INVISIBLE (-3575 5850);
FORCEADD TAP..6
R 2
(-3075 5700);
FORCEPROP 3 LASTPIN (-3125 5700) SIG_NAME GMI_CPU1_G2_CPU0_G0_TX_DP<14>
J 0
(-3115 5710);
DISPLAY 0.659574 (-3115 5710);
PAINT MONO (-3115 5710);
DISPLAY INVISIBLE (-3115 5710);
FORCEPROP 1 LASTPIN (-3125 5700) BN 14
J 2
(-3073 5708);
DISPLAY 0.489362 (-3073 5708);
PAINT MONO (-3073 5708);
FORCEPROP 2 LAST BOM_COST IO_SLOT
J 0
(-3575 5800);
DISPLAY 0.829787 (-3575 5800);
DISPLAY INVISIBLE (-3575 5800);
FORCEPROP 2 LAST CDS_LIB mstr_standard
J 0
(-3075 5700);
DISPLAY INVISIBLE (-3075 5700);
FORCEPROP 1 LAST BODY_TYPE PLUMBING
J 2
(-3075 5650);
DISPLAY 0.702128 (-3075 5650);
PAINT GREEN (-3075 5650);
DISPLAY INVISIBLE (-3075 5650);
FORCEPROP 1 LAST HDL_TAP TRUE
J 2
(-3400 5575);
DISPLAY 0.702128 (-3400 5575);
PAINT GREEN (-3400 5575);
DISPLAY INVISIBLE (-3400 5575);
FORCEPROP 1 LAST PATH I199
J 2
(-3073 5700);
DISPLAY 0.872340 (-3073 5700);
PAINT GREEN (-3073 5700);
DISPLAY INVISIBLE (-3073 5700);
FORCEPROP 2 LAST ROOM RISER1
J 0
(-3575 5750);
DISPLAY 0.829787 (-3575 5750);
PAINT RED (-3575 5750);
DISPLAY INVISIBLE (-3575 5750);
FORCEADD TAP..6
R 2
(-3075 5400);
FORCEPROP 3 LASTPIN (-3125 5400) SIG_NAME GMI_CPU1_G2_CPU0_G0_TX_DP<11>
J 0
(-3115 5410);
DISPLAY 0.659574 (-3115 5410);
PAINT MONO (-3115 5410);
DISPLAY INVISIBLE (-3115 5410);
FORCEPROP 1 LASTPIN (-3125 5400) BN 11
J 2
(-3073 5408);
DISPLAY 0.489362 (-3073 5408);
PAINT MONO (-3073 5408);
FORCEPROP 2 LAST BOM_COST IO_SLOT
J 0
(-3575 5500);
DISPLAY 0.829787 (-3575 5500);
DISPLAY INVISIBLE (-3575 5500);
FORCEPROP 2 LAST CDS_LIB standard
J 0
(-3075 5400);
DISPLAY INVISIBLE (-3075 5400);
FORCEPROP 1 LAST BODY_TYPE PLUMBING
J 2
(-3075 5350);
DISPLAY 0.702128 (-3075 5350);
PAINT GREEN (-3075 5350);
DISPLAY INVISIBLE (-3075 5350);
FORCEPROP 1 LAST HDL_TAP TRUE
J 2
(-3400 5275);
DISPLAY 0.702128 (-3400 5275);
PAINT GREEN (-3400 5275);
DISPLAY INVISIBLE (-3400 5275);
FORCEPROP 1 LAST PATH I202
J 2
(-3073 5400);
DISPLAY 0.872340 (-3073 5400);
PAINT GREEN (-3073 5400);
DISPLAY INVISIBLE (-3073 5400);
FORCEPROP 2 LAST ROOM RISER1
J 0
(-3575 5450);
DISPLAY 0.829787 (-3575 5450);
PAINT RED (-3575 5450);
DISPLAY INVISIBLE (-3575 5450);
FORCEADD TAP..6
R 2
(-3075 5600);
FORCEPROP 3 LASTPIN (-3125 5600) SIG_NAME GMI_CPU1_G2_CPU0_G0_TX_DP<13>
J 0
(-3115 5610);
DISPLAY 0.659574 (-3115 5610);
PAINT MONO (-3115 5610);
DISPLAY INVISIBLE (-3115 5610);
FORCEPROP 1 LASTPIN (-3125 5600) BN 13
J 2
(-3073 5608);
DISPLAY 0.489362 (-3073 5608);
PAINT MONO (-3073 5608);
FORCEPROP 2 LAST BOM_COST IO_SLOT
J 0
(-3575 5700);
DISPLAY 0.829787 (-3575 5700);
DISPLAY INVISIBLE (-3575 5700);
FORCEPROP 2 LAST CDS_LIB standard
J 0
(-3075 5600);
DISPLAY INVISIBLE (-3075 5600);
FORCEPROP 1 LAST BODY_TYPE PLUMBING
J 2
(-3075 5550);
DISPLAY 0.702128 (-3075 5550);
PAINT GREEN (-3075 5550);
DISPLAY INVISIBLE (-3075 5550);
FORCEPROP 1 LAST HDL_TAP TRUE
J 2
(-3400 5475);
DISPLAY 0.702128 (-3400 5475);
PAINT GREEN (-3400 5475);
DISPLAY INVISIBLE (-3400 5475);
FORCEPROP 1 LAST PATH I203
J 2
(-3073 5600);
DISPLAY 0.872340 (-3073 5600);
PAINT GREEN (-3073 5600);
DISPLAY INVISIBLE (-3073 5600);
FORCEPROP 2 LAST ROOM RISER1
J 0
(-3575 5650);
DISPLAY 0.829787 (-3575 5650);
PAINT RED (-3575 5650);
DISPLAY INVISIBLE (-3575 5650);
FORCEADD TAP..6
R 2
(-3075 5500);
FORCEPROP 3 LASTPIN (-3125 5500) SIG_NAME GMI_CPU1_G2_CPU0_G0_TX_DP<12>
J 0
(-3115 5510);
DISPLAY 0.659574 (-3115 5510);
PAINT MONO (-3115 5510);
DISPLAY INVISIBLE (-3115 5510);
FORCEPROP 1 LASTPIN (-3125 5500) BN 12
J 2
(-3073 5508);
DISPLAY 0.489362 (-3073 5508);
PAINT MONO (-3073 5508);
FORCEPROP 2 LAST BOM_COST IO_SLOT
J 0
(-3575 5600);
DISPLAY 0.829787 (-3575 5600);
DISPLAY INVISIBLE (-3575 5600);
FORCEPROP 2 LAST CDS_LIB standard
J 0
(-3075 5500);
DISPLAY INVISIBLE (-3075 5500);
FORCEPROP 1 LAST BODY_TYPE PLUMBING
J 2
(-3075 5450);
DISPLAY 0.702128 (-3075 5450);
PAINT GREEN (-3075 5450);
DISPLAY INVISIBLE (-3075 5450);
FORCEPROP 1 LAST HDL_TAP TRUE
J 2
(-3400 5375);
DISPLAY 0.702128 (-3400 5375);
PAINT GREEN (-3400 5375);
DISPLAY INVISIBLE (-3400 5375);
FORCEPROP 1 LAST PATH I204
J 2
(-3073 5500);
DISPLAY 0.872340 (-3073 5500);
PAINT GREEN (-3073 5500);
DISPLAY INVISIBLE (-3073 5500);
FORCEPROP 2 LAST ROOM RISER1
J 0
(-3575 5550);
DISPLAY 0.829787 (-3575 5550);
PAINT RED (-3575 5550);
DISPLAY INVISIBLE (-3575 5550);
FORCEADD TAP..6
R 2
(-3075 5200);
FORCEPROP 3 LASTPIN (-3125 5200) SIG_NAME GMI_CPU1_G2_CPU0_G0_TX_DP<9>
J 0
(-3115 5210);
DISPLAY 0.659574 (-3115 5210);
PAINT MONO (-3115 5210);
DISPLAY INVISIBLE (-3115 5210);
FORCEPROP 1 LASTPIN (-3125 5200) BN 9
J 2
(-3073 5208);
DISPLAY 0.489362 (-3073 5208);
PAINT MONO (-3073 5208);
FORCEPROP 2 LAST BOM_COST IO_SLOT
J 0
(-3575 5300);
DISPLAY 0.829787 (-3575 5300);
DISPLAY INVISIBLE (-3575 5300);
FORCEPROP 2 LAST CDS_LIB standard
J 0
(-3075 5200);
DISPLAY INVISIBLE (-3075 5200);
FORCEPROP 1 LAST BODY_TYPE PLUMBING
J 2
(-3075 5150);
DISPLAY 0.702128 (-3075 5150);
PAINT GREEN (-3075 5150);
DISPLAY INVISIBLE (-3075 5150);
FORCEPROP 1 LAST HDL_TAP TRUE
J 2
(-3400 5075);
DISPLAY 0.702128 (-3400 5075);
PAINT GREEN (-3400 5075);
DISPLAY INVISIBLE (-3400 5075);
FORCEPROP 1 LAST PATH I208
J 2
(-3073 5200);
DISPLAY 0.872340 (-3073 5200);
PAINT GREEN (-3073 5200);
DISPLAY INVISIBLE (-3073 5200);
FORCEPROP 2 LAST ROOM RISER1
J 0
(-3575 5250);
DISPLAY 0.829787 (-3575 5250);
PAINT RED (-3575 5250);
DISPLAY INVISIBLE (-3575 5250);
FORCEADD TAP..6
R 2
(-3075 5300);
FORCEPROP 3 LASTPIN (-3125 5300) SIG_NAME GMI_CPU1_G2_CPU0_G0_TX_DP<10>
J 0
(-3115 5310);
DISPLAY 0.659574 (-3115 5310);
PAINT MONO (-3115 5310);
DISPLAY INVISIBLE (-3115 5310);
FORCEPROP 1 LASTPIN (-3125 5300) BN 10
J 2
(-3073 5308);
DISPLAY 0.489362 (-3073 5308);
PAINT MONO (-3073 5308);
FORCEPROP 2 LAST BOM_COST IO_SLOT
J 0
(-3575 5400);
DISPLAY 0.829787 (-3575 5400);
DISPLAY INVISIBLE (-3575 5400);
FORCEPROP 2 LAST CDS_LIB standard
J 0
(-3075 5300);
DISPLAY INVISIBLE (-3075 5300);
FORCEPROP 1 LAST BODY_TYPE PLUMBING
J 2
(-3075 5250);
DISPLAY 0.702128 (-3075 5250);
PAINT GREEN (-3075 5250);
DISPLAY INVISIBLE (-3075 5250);
FORCEPROP 1 LAST HDL_TAP TRUE
J 2
(-3400 5175);
DISPLAY 0.702128 (-3400 5175);
PAINT GREEN (-3400 5175);
DISPLAY INVISIBLE (-3400 5175);
FORCEPROP 1 LAST PATH I209
J 2
(-3073 5300);
DISPLAY 0.872340 (-3073 5300);
PAINT GREEN (-3073 5300);
DISPLAY INVISIBLE (-3073 5300);
FORCEPROP 2 LAST ROOM RISER1
J 0
(-3575 5350);
DISPLAY 0.829787 (-3575 5350);
PAINT RED (-3575 5350);
DISPLAY INVISIBLE (-3575 5350);
FORCEADD TAP..6
R 2
(-3075 5100);
FORCEPROP 3 LASTPIN (-3125 5100) SIG_NAME GMI_CPU1_G2_CPU0_G0_TX_DP<8>
J 0
(-3115 5110);
DISPLAY 0.659574 (-3115 5110);
PAINT MONO (-3115 5110);
DISPLAY INVISIBLE (-3115 5110);
FORCEPROP 1 LASTPIN (-3125 5100) BN 8
J 2
(-3073 5108);
DISPLAY 0.489362 (-3073 5108);
PAINT MONO (-3073 5108);
FORCEPROP 2 LAST BOM_COST IO_SLOT
J 0
(-3575 5200);
DISPLAY 0.829787 (-3575 5200);
DISPLAY INVISIBLE (-3575 5200);
FORCEPROP 2 LAST CDS_LIB standard
J 0
(-3075 5100);
DISPLAY INVISIBLE (-3075 5100);
FORCEPROP 1 LAST BODY_TYPE PLUMBING
J 2
(-3075 5050);
DISPLAY 0.702128 (-3075 5050);
PAINT GREEN (-3075 5050);
DISPLAY INVISIBLE (-3075 5050);
FORCEPROP 1 LAST HDL_TAP TRUE
J 2
(-3400 4975);
DISPLAY 0.702128 (-3400 4975);
PAINT GREEN (-3400 4975);
DISPLAY INVISIBLE (-3400 4975);
FORCEPROP 1 LAST PATH I212
J 2
(-3073 5100);
DISPLAY 0.872340 (-3073 5100);
PAINT GREEN (-3073 5100);
DISPLAY INVISIBLE (-3073 5100);
FORCEPROP 2 LAST ROOM RISER1
J 0
(-3575 5150);
DISPLAY 0.829787 (-3575 5150);
PAINT RED (-3575 5150);
DISPLAY INVISIBLE (-3575 5150);
FORCEADD TAP..6
R 2
(-3075 5000);
FORCEPROP 3 LASTPIN (-3125 5000) SIG_NAME GMI_CPU1_G2_CPU0_G0_TX_DP<7>
J 0
(-3115 5010);
DISPLAY 0.659574 (-3115 5010);
PAINT MONO (-3115 5010);
DISPLAY INVISIBLE (-3115 5010);
FORCEPROP 1 LASTPIN (-3125 5000) BN 7
J 2
(-3073 5008);
DISPLAY 0.489362 (-3073 5008);
PAINT MONO (-3073 5008);
FORCEPROP 2 LAST BOM_COST IO_SLOT
J 0
(-3575 5100);
DISPLAY 0.829787 (-3575 5100);
DISPLAY INVISIBLE (-3575 5100);
FORCEPROP 2 LAST CDS_LIB standard
J 0
(-3075 5000);
DISPLAY INVISIBLE (-3075 5000);
FORCEPROP 1 LAST BODY_TYPE PLUMBING
J 2
(-3075 4950);
DISPLAY 0.702128 (-3075 4950);
PAINT GREEN (-3075 4950);
DISPLAY INVISIBLE (-3075 4950);
FORCEPROP 1 LAST HDL_TAP TRUE
J 2
(-3400 4875);
DISPLAY 0.702128 (-3400 4875);
PAINT GREEN (-3400 4875);
DISPLAY INVISIBLE (-3400 4875);
FORCEPROP 1 LAST PATH I213
J 2
(-3073 5000);
DISPLAY 0.872340 (-3073 5000);
PAINT GREEN (-3073 5000);
DISPLAY INVISIBLE (-3073 5000);
FORCEPROP 2 LAST ROOM RISER1
J 0
(-3575 5050);
DISPLAY 0.829787 (-3575 5050);
PAINT RED (-3575 5050);
DISPLAY INVISIBLE (-3575 5050);
FORCEADD TAP..6
R 2
(-3075 4900);
FORCEPROP 3 LASTPIN (-3125 4900) SIG_NAME GMI_CPU1_G2_CPU0_G0_TX_DP<6>
J 0
(-3115 4910);
DISPLAY 0.659574 (-3115 4910);
PAINT MONO (-3115 4910);
DISPLAY INVISIBLE (-3115 4910);
FORCEPROP 1 LASTPIN (-3125 4900) BN 6
J 2
(-3073 4908);
DISPLAY 0.489362 (-3073 4908);
PAINT MONO (-3073 4908);
FORCEPROP 2 LAST BOM_COST IO_SLOT
J 0
(-3575 5000);
DISPLAY 0.829787 (-3575 5000);
DISPLAY INVISIBLE (-3575 5000);
FORCEPROP 2 LAST CDS_LIB standard
J 0
(-3075 4900);
DISPLAY INVISIBLE (-3075 4900);
FORCEPROP 1 LAST BODY_TYPE PLUMBING
J 2
(-3075 4850);
DISPLAY 0.702128 (-3075 4850);
PAINT GREEN (-3075 4850);
DISPLAY INVISIBLE (-3075 4850);
FORCEPROP 1 LAST HDL_TAP TRUE
J 2
(-3400 4775);
DISPLAY 0.702128 (-3400 4775);
PAINT GREEN (-3400 4775);
DISPLAY INVISIBLE (-3400 4775);
FORCEPROP 1 LAST PATH I214
J 2
(-3073 4900);
DISPLAY 0.872340 (-3073 4900);
PAINT GREEN (-3073 4900);
DISPLAY INVISIBLE (-3073 4900);
FORCEPROP 2 LAST ROOM RISER1
J 0
(-3575 4950);
DISPLAY 0.829787 (-3575 4950);
PAINT RED (-3575 4950);
DISPLAY INVISIBLE (-3575 4950);
FORCEADD TAP..6
R 2
(-3075 4700);
FORCEPROP 3 LASTPIN (-3125 4700) SIG_NAME GMI_CPU1_G2_CPU0_G0_TX_DP<4>
J 0
(-3115 4710);
DISPLAY 0.659574 (-3115 4710);
PAINT MONO (-3115 4710);
DISPLAY INVISIBLE (-3115 4710);
FORCEPROP 1 LASTPIN (-3125 4700) BN 4
J 2
(-3073 4708);
DISPLAY 0.489362 (-3073 4708);
PAINT MONO (-3073 4708);
FORCEPROP 2 LAST BOM_COST IO_SLOT
J 0
(-3575 4800);
DISPLAY 0.829787 (-3575 4800);
DISPLAY INVISIBLE (-3575 4800);
FORCEPROP 2 LAST CDS_LIB standard
J 0
(-3075 4700);
DISPLAY INVISIBLE (-3075 4700);
FORCEPROP 1 LAST BODY_TYPE PLUMBING
J 2
(-3075 4650);
DISPLAY 0.702128 (-3075 4650);
PAINT GREEN (-3075 4650);
DISPLAY INVISIBLE (-3075 4650);
FORCEPROP 1 LAST HDL_TAP TRUE
J 2
(-3400 4575);
DISPLAY 0.702128 (-3400 4575);
PAINT GREEN (-3400 4575);
DISPLAY INVISIBLE (-3400 4575);
FORCEPROP 1 LAST PATH I218
J 2
(-3073 4700);
DISPLAY 0.872340 (-3073 4700);
PAINT GREEN (-3073 4700);
DISPLAY INVISIBLE (-3073 4700);
FORCEPROP 2 LAST ROOM RISER1
J 0
(-3575 4750);
DISPLAY 0.829787 (-3575 4750);
PAINT RED (-3575 4750);
DISPLAY INVISIBLE (-3575 4750);
FORCEADD TAP..6
R 2
(-3075 4800);
FORCEPROP 3 LASTPIN (-3125 4800) SIG_NAME GMI_CPU1_G2_CPU0_G0_TX_DP<5>
J 0
(-3115 4810);
DISPLAY 0.659574 (-3115 4810);
PAINT MONO (-3115 4810);
DISPLAY INVISIBLE (-3115 4810);
FORCEPROP 1 LASTPIN (-3125 4800) BN 5
J 2
(-3073 4808);
DISPLAY 0.489362 (-3073 4808);
PAINT MONO (-3073 4808);
FORCEPROP 2 LAST BOM_COST IO_SLOT
J 0
(-3575 4900);
DISPLAY 0.829787 (-3575 4900);
DISPLAY INVISIBLE (-3575 4900);
FORCEPROP 2 LAST CDS_LIB standard
J 0
(-3075 4800);
DISPLAY INVISIBLE (-3075 4800);
FORCEPROP 1 LAST BODY_TYPE PLUMBING
J 2
(-3075 4750);
DISPLAY 0.702128 (-3075 4750);
PAINT GREEN (-3075 4750);
DISPLAY INVISIBLE (-3075 4750);
FORCEPROP 1 LAST HDL_TAP TRUE
J 2
(-3400 4675);
DISPLAY 0.702128 (-3400 4675);
PAINT GREEN (-3400 4675);
DISPLAY INVISIBLE (-3400 4675);
FORCEPROP 1 LAST PATH I219
J 2
(-3073 4800);
DISPLAY 0.872340 (-3073 4800);
PAINT GREEN (-3073 4800);
DISPLAY INVISIBLE (-3073 4800);
FORCEPROP 2 LAST ROOM RISER1
J 0
(-3575 4850);
DISPLAY 0.829787 (-3575 4850);
PAINT RED (-3575 4850);
DISPLAY INVISIBLE (-3575 4850);
FORCEADD TAP..6
R 2
(-3075 4600);
FORCEPROP 3 LASTPIN (-3125 4600) SIG_NAME GMI_CPU1_G2_CPU0_G0_TX_DP<3>
J 0
(-3115 4610);
DISPLAY 0.659574 (-3115 4610);
PAINT MONO (-3115 4610);
DISPLAY INVISIBLE (-3115 4610);
FORCEPROP 1 LASTPIN (-3125 4600) BN 3
J 2
(-3073 4608);
DISPLAY 0.489362 (-3073 4608);
PAINT MONO (-3073 4608);
FORCEPROP 2 LAST BOM_COST IO_SLOT
J 0
(-3575 4700);
DISPLAY 0.829787 (-3575 4700);
DISPLAY INVISIBLE (-3575 4700);
FORCEPROP 2 LAST CDS_LIB standard
J 0
(-3075 4600);
DISPLAY INVISIBLE (-3075 4600);
FORCEPROP 1 LAST BODY_TYPE PLUMBING
J 2
(-3075 4550);
DISPLAY 0.702128 (-3075 4550);
PAINT GREEN (-3075 4550);
DISPLAY INVISIBLE (-3075 4550);
FORCEPROP 1 LAST HDL_TAP TRUE
J 2
(-3400 4475);
DISPLAY 0.702128 (-3400 4475);
PAINT GREEN (-3400 4475);
DISPLAY INVISIBLE (-3400 4475);
FORCEPROP 1 LAST PATH I222
J 2
(-3073 4600);
DISPLAY 0.872340 (-3073 4600);
PAINT GREEN (-3073 4600);
DISPLAY INVISIBLE (-3073 4600);
FORCEPROP 2 LAST ROOM RISER1
J 0
(-3575 4650);
DISPLAY 0.829787 (-3575 4650);
PAINT RED (-3575 4650);
DISPLAY INVISIBLE (-3575 4650);
FORCEADD TAP..6
R 2
(-3075 4500);
FORCEPROP 3 LASTPIN (-3125 4500) SIG_NAME GMI_CPU1_G2_CPU0_G0_TX_DP<2>
J 0
(-3115 4510);
DISPLAY 0.659574 (-3115 4510);
PAINT MONO (-3115 4510);
DISPLAY INVISIBLE (-3115 4510);
FORCEPROP 1 LASTPIN (-3125 4500) BN 2
J 2
(-3073 4508);
DISPLAY 0.489362 (-3073 4508);
PAINT MONO (-3073 4508);
FORCEPROP 2 LAST BOM_COST IO_SLOT
J 0
(-3575 4600);
DISPLAY 0.829787 (-3575 4600);
DISPLAY INVISIBLE (-3575 4600);
FORCEPROP 2 LAST CDS_LIB standard
J 0
(-3075 4500);
DISPLAY INVISIBLE (-3075 4500);
FORCEPROP 1 LAST BODY_TYPE PLUMBING
J 2
(-3075 4450);
DISPLAY 0.702128 (-3075 4450);
PAINT GREEN (-3075 4450);
DISPLAY INVISIBLE (-3075 4450);
FORCEPROP 1 LAST HDL_TAP TRUE
J 2
(-3400 4375);
DISPLAY 0.702128 (-3400 4375);
PAINT GREEN (-3400 4375);
DISPLAY INVISIBLE (-3400 4375);
FORCEPROP 1 LAST PATH I223
J 2
(-3073 4500);
DISPLAY 0.872340 (-3073 4500);
PAINT GREEN (-3073 4500);
DISPLAY INVISIBLE (-3073 4500);
FORCEPROP 2 LAST ROOM RISER1
J 0
(-3575 4550);
DISPLAY 0.829787 (-3575 4550);
PAINT RED (-3575 4550);
DISPLAY INVISIBLE (-3575 4550);
FORCEADD TAP..6
R 2
(-3075 4400);
FORCEPROP 3 LASTPIN (-3125 4400) SIG_NAME GMI_CPU1_G2_CPU0_G0_TX_DP<1>
J 0
(-3115 4410);
DISPLAY 0.659574 (-3115 4410);
PAINT MONO (-3115 4410);
DISPLAY INVISIBLE (-3115 4410);
FORCEPROP 1 LASTPIN (-3125 4400) BN 1
J 2
(-3073 4408);
DISPLAY 0.489362 (-3073 4408);
PAINT MONO (-3073 4408);
FORCEPROP 2 LAST BOM_COST IO_SLOT
J 0
(-3575 4500);
DISPLAY 0.829787 (-3575 4500);
DISPLAY INVISIBLE (-3575 4500);
FORCEPROP 2 LAST CDS_LIB standard
J 0
(-3075 4400);
DISPLAY INVISIBLE (-3075 4400);
FORCEPROP 1 LAST BODY_TYPE PLUMBING
J 2
(-3075 4350);
DISPLAY 0.702128 (-3075 4350);
PAINT GREEN (-3075 4350);
DISPLAY INVISIBLE (-3075 4350);
FORCEPROP 1 LAST HDL_TAP TRUE
J 2
(-3400 4275);
DISPLAY 0.702128 (-3400 4275);
PAINT GREEN (-3400 4275);
DISPLAY INVISIBLE (-3400 4275);
FORCEPROP 1 LAST PATH I224
J 2
(-3073 4400);
DISPLAY 0.872340 (-3073 4400);
PAINT GREEN (-3073 4400);
DISPLAY INVISIBLE (-3073 4400);
FORCEPROP 2 LAST ROOM RISER1
J 0
(-3575 4450);
DISPLAY 0.829787 (-3575 4450);
PAINT RED (-3575 4450);
DISPLAY INVISIBLE (-3575 4450);
FORCEADD TAP..6
R 2
(-3075 4300);
FORCEPROP 3 LASTPIN (-3125 4300) SIG_NAME GMI_CPU1_G2_CPU0_G0_TX_DP<0>
J 0
(-3115 4310);
DISPLAY 0.659574 (-3115 4310);
PAINT MONO (-3115 4310);
DISPLAY INVISIBLE (-3115 4310);
FORCEPROP 1 LASTPIN (-3125 4300) BN 0
J 2
(-3073 4308);
DISPLAY 0.489362 (-3073 4308);
PAINT MONO (-3073 4308);
FORCEPROP 2 LAST BOM_COST IO_SLOT
J 0
(-3575 4400);
DISPLAY 0.829787 (-3575 4400);
DISPLAY INVISIBLE (-3575 4400);
FORCEPROP 2 LAST CDS_LIB standard
J 0
(-3075 4300);
DISPLAY INVISIBLE (-3075 4300);
FORCEPROP 1 LAST BODY_TYPE PLUMBING
J 2
(-3075 4250);
DISPLAY 0.702128 (-3075 4250);
PAINT GREEN (-3075 4250);
DISPLAY INVISIBLE (-3075 4250);
FORCEPROP 1 LAST HDL_TAP TRUE
J 2
(-3400 4175);
DISPLAY 0.702128 (-3400 4175);
PAINT GREEN (-3400 4175);
DISPLAY INVISIBLE (-3400 4175);
FORCEPROP 1 LAST PATH I225
J 2
(-3073 4300);
DISPLAY 0.872340 (-3073 4300);
PAINT GREEN (-3073 4300);
DISPLAY INVISIBLE (-3073 4300);
FORCEPROP 2 LAST ROOM RISER1
J 0
(-3575 4350);
DISPLAY 0.829787 (-3575 4350);
PAINT RED (-3575 4350);
DISPLAY INVISIBLE (-3575 4350);
FORCEADD OFFPAGE..2
(-1775 3350);
FORCEPROP 2 LAST $XR0 22 
J 0
(-1586 3350);
DISPLAY 0.638298 (-1586 3350);
PAINT MONO (-1586 3350);
FORCEPROP 2 LAST CDS_LIB standard
J 0
(-1775 3350);
DISPLAY INVISIBLE (-1775 3350);
FORCEPROP 1 LAST OFFPAGE TRUE
J 0
(-1450 3225);
DISPLAY 0.872340 (-1450 3225);
PAINT GREEN (-1450 3225);
DISPLAY INVISIBLE (-1450 3225);
FORCEPROP 1 LAST COMMENT_BODY TRUE
J 0
(-1820 3255);
DISPLAY 0.872340 (-1820 3255);
PAINT GREEN (-1820 3255);
DISPLAY INVISIBLE (-1820 3255);
FORCEPROP 2 LAST PATH I228
J 0
(-1575 3400);
DISPLAY 1.021277 (-1575 3400);
DISPLAY INVISIBLE (-1575 3400);
FORCEADD TAP..6
R 2
(-3050 3125);
FORCEPROP 3 LASTPIN (-3100 3125) SIG_NAME GMI_CPU1_G3_CPU0_G1_TX_DP<15>
J 0
(-3090 3135);
DISPLAY 0.659574 (-3090 3135);
PAINT MONO (-3090 3135);
DISPLAY INVISIBLE (-3090 3135);
FORCEPROP 1 LASTPIN (-3100 3125) BN 15
J 2
(-3048 3133);
DISPLAY 0.489362 (-3048 3133);
PAINT MONO (-3048 3133);
FORCEPROP 2 LAST CDS_LIB mstr_standard
J 0
(-3050 3125);
DISPLAY INVISIBLE (-3050 3125);
FORCEPROP 2 LAST BOM_COST IO_SLOT
J 0
(-3550 3225);
DISPLAY 0.829787 (-3550 3225);
DISPLAY INVISIBLE (-3550 3225);
FORCEPROP 1 LAST BODY_TYPE PLUMBING
J 2
(-3050 3075);
DISPLAY 0.702128 (-3050 3075);
PAINT GREEN (-3050 3075);
DISPLAY INVISIBLE (-3050 3075);
FORCEPROP 1 LAST HDL_TAP TRUE
J 2
(-3375 3000);
DISPLAY 0.702128 (-3375 3000);
PAINT GREEN (-3375 3000);
DISPLAY INVISIBLE (-3375 3000);
FORCEPROP 1 LAST PATH I241
J 2
(-3048 3125);
DISPLAY 0.872340 (-3048 3125);
PAINT GREEN (-3048 3125);
DISPLAY INVISIBLE (-3048 3125);
FORCEPROP 2 LAST ROOM RISER1
J 0
(-3550 3175);
DISPLAY 0.829787 (-3550 3175);
PAINT RED (-3550 3175);
DISPLAY INVISIBLE (-3550 3175);
FORCEADD TAP..6
R 2
(-3050 2925);
FORCEPROP 3 LASTPIN (-3100 2925) SIG_NAME GMI_CPU1_G3_CPU0_G1_TX_DP<13>
J 0
(-3090 2935);
DISPLAY 0.659574 (-3090 2935);
PAINT MONO (-3090 2935);
DISPLAY INVISIBLE (-3090 2935);
FORCEPROP 1 LASTPIN (-3100 2925) BN 13
J 2
(-3048 2933);
DISPLAY 0.489362 (-3048 2933);
PAINT MONO (-3048 2933);
FORCEPROP 2 LAST CDS_LIB standard
J 0
(-3050 2925);
DISPLAY INVISIBLE (-3050 2925);
FORCEPROP 2 LAST BOM_COST IO_SLOT
J 0
(-3550 3025);
DISPLAY 0.829787 (-3550 3025);
DISPLAY INVISIBLE (-3550 3025);
FORCEPROP 1 LAST BODY_TYPE PLUMBING
J 2
(-3050 2875);
DISPLAY 0.702128 (-3050 2875);
PAINT GREEN (-3050 2875);
DISPLAY INVISIBLE (-3050 2875);
FORCEPROP 1 LAST HDL_TAP TRUE
J 2
(-3375 2800);
DISPLAY 0.702128 (-3375 2800);
PAINT GREEN (-3375 2800);
DISPLAY INVISIBLE (-3375 2800);
FORCEPROP 1 LAST PATH I242
J 2
(-3048 2925);
DISPLAY 0.872340 (-3048 2925);
PAINT GREEN (-3048 2925);
DISPLAY INVISIBLE (-3048 2925);
FORCEPROP 2 LAST ROOM RISER1
J 0
(-3550 2975);
DISPLAY 0.829787 (-3550 2975);
PAINT RED (-3550 2975);
DISPLAY INVISIBLE (-3550 2975);
FORCEADD TAP..6
R 2
(-3050 2825);
FORCEPROP 3 LASTPIN (-3100 2825) SIG_NAME GMI_CPU1_G3_CPU0_G1_TX_DP<12>
J 0
(-3090 2835);
DISPLAY 0.659574 (-3090 2835);
PAINT MONO (-3090 2835);
DISPLAY INVISIBLE (-3090 2835);
FORCEPROP 1 LASTPIN (-3100 2825) BN 12
J 2
(-3048 2833);
DISPLAY 0.489362 (-3048 2833);
PAINT MONO (-3048 2833);
FORCEPROP 2 LAST CDS_LIB standard
J 0
(-3050 2825);
DISPLAY INVISIBLE (-3050 2825);
FORCEPROP 2 LAST BOM_COST IO_SLOT
J 0
(-3550 2925);
DISPLAY 0.829787 (-3550 2925);
DISPLAY INVISIBLE (-3550 2925);
FORCEPROP 1 LAST BODY_TYPE PLUMBING
J 2
(-3050 2775);
DISPLAY 0.702128 (-3050 2775);
PAINT GREEN (-3050 2775);
DISPLAY INVISIBLE (-3050 2775);
FORCEPROP 1 LAST HDL_TAP TRUE
J 2
(-3375 2700);
DISPLAY 0.702128 (-3375 2700);
PAINT GREEN (-3375 2700);
DISPLAY INVISIBLE (-3375 2700);
FORCEPROP 1 LAST PATH I243
J 2
(-3048 2825);
DISPLAY 0.872340 (-3048 2825);
PAINT GREEN (-3048 2825);
DISPLAY INVISIBLE (-3048 2825);
FORCEPROP 2 LAST ROOM RISER1
J 0
(-3550 2875);
DISPLAY 0.829787 (-3550 2875);
PAINT RED (-3550 2875);
DISPLAY INVISIBLE (-3550 2875);
FORCEADD TAP..6
R 2
(-3050 3025);
FORCEPROP 3 LASTPIN (-3100 3025) SIG_NAME GMI_CPU1_G3_CPU0_G1_TX_DP<14>
J 0
(-3090 3035);
DISPLAY 0.659574 (-3090 3035);
PAINT MONO (-3090 3035);
DISPLAY INVISIBLE (-3090 3035);
FORCEPROP 1 LASTPIN (-3100 3025) BN 14
J 2
(-3048 3033);
DISPLAY 0.489362 (-3048 3033);
PAINT MONO (-3048 3033);
FORCEPROP 2 LAST CDS_LIB mstr_standard
J 0
(-3050 3025);
DISPLAY INVISIBLE (-3050 3025);
FORCEPROP 2 LAST BOM_COST IO_SLOT
J 0
(-3550 3125);
DISPLAY 0.829787 (-3550 3125);
DISPLAY INVISIBLE (-3550 3125);
FORCEPROP 1 LAST BODY_TYPE PLUMBING
J 2
(-3050 2975);
DISPLAY 0.702128 (-3050 2975);
PAINT GREEN (-3050 2975);
DISPLAY INVISIBLE (-3050 2975);
FORCEPROP 1 LAST HDL_TAP TRUE
J 2
(-3375 2900);
DISPLAY 0.702128 (-3375 2900);
PAINT GREEN (-3375 2900);
DISPLAY INVISIBLE (-3375 2900);
FORCEPROP 1 LAST PATH I244
J 2
(-3048 3025);
DISPLAY 0.872340 (-3048 3025);
PAINT GREEN (-3048 3025);
DISPLAY INVISIBLE (-3048 3025);
FORCEPROP 2 LAST ROOM RISER1
J 0
(-3550 3075);
DISPLAY 0.829787 (-3550 3075);
PAINT RED (-3550 3075);
DISPLAY INVISIBLE (-3550 3075);
FORCEADD TAP..6
R 2
(-3050 2725);
FORCEPROP 3 LASTPIN (-3100 2725) SIG_NAME GMI_CPU1_G3_CPU0_G1_TX_DP<11>
J 0
(-3090 2735);
DISPLAY 0.659574 (-3090 2735);
PAINT MONO (-3090 2735);
DISPLAY INVISIBLE (-3090 2735);
FORCEPROP 1 LASTPIN (-3100 2725) BN 11
J 2
(-3048 2733);
DISPLAY 0.489362 (-3048 2733);
PAINT MONO (-3048 2733);
FORCEPROP 2 LAST CDS_LIB standard
J 0
(-3050 2725);
DISPLAY INVISIBLE (-3050 2725);
FORCEPROP 2 LAST BOM_COST IO_SLOT
J 0
(-3550 2825);
DISPLAY 0.829787 (-3550 2825);
DISPLAY INVISIBLE (-3550 2825);
FORCEPROP 1 LAST BODY_TYPE PLUMBING
J 2
(-3050 2675);
DISPLAY 0.702128 (-3050 2675);
PAINT GREEN (-3050 2675);
DISPLAY INVISIBLE (-3050 2675);
FORCEPROP 1 LAST HDL_TAP TRUE
J 2
(-3375 2600);
DISPLAY 0.702128 (-3375 2600);
PAINT GREEN (-3375 2600);
DISPLAY INVISIBLE (-3375 2600);
FORCEPROP 1 LAST PATH I245
J 2
(-3048 2725);
DISPLAY 0.872340 (-3048 2725);
PAINT GREEN (-3048 2725);
DISPLAY INVISIBLE (-3048 2725);
FORCEPROP 2 LAST ROOM RISER1
J 0
(-3550 2775);
DISPLAY 0.829787 (-3550 2775);
PAINT RED (-3550 2775);
DISPLAY INVISIBLE (-3550 2775);
FORCEADD TAP..6
R 2
(-3050 2625);
FORCEPROP 3 LASTPIN (-3100 2625) SIG_NAME GMI_CPU1_G3_CPU0_G1_TX_DP<10>
J 0
(-3090 2635);
DISPLAY 0.659574 (-3090 2635);
PAINT MONO (-3090 2635);
DISPLAY INVISIBLE (-3090 2635);
FORCEPROP 1 LASTPIN (-3100 2625) BN 10
J 2
(-3048 2633);
DISPLAY 0.489362 (-3048 2633);
PAINT MONO (-3048 2633);
FORCEPROP 2 LAST CDS_LIB standard
J 0
(-3050 2625);
DISPLAY INVISIBLE (-3050 2625);
FORCEPROP 2 LAST BOM_COST IO_SLOT
J 0
(-3550 2725);
DISPLAY 0.829787 (-3550 2725);
DISPLAY INVISIBLE (-3550 2725);
FORCEPROP 1 LAST BODY_TYPE PLUMBING
J 2
(-3050 2575);
DISPLAY 0.702128 (-3050 2575);
PAINT GREEN (-3050 2575);
DISPLAY INVISIBLE (-3050 2575);
FORCEPROP 1 LAST HDL_TAP TRUE
J 2
(-3375 2500);
DISPLAY 0.702128 (-3375 2500);
PAINT GREEN (-3375 2500);
DISPLAY INVISIBLE (-3375 2500);
FORCEPROP 1 LAST PATH I246
J 2
(-3048 2625);
DISPLAY 0.872340 (-3048 2625);
PAINT GREEN (-3048 2625);
DISPLAY INVISIBLE (-3048 2625);
FORCEPROP 2 LAST ROOM RISER1
J 0
(-3550 2675);
DISPLAY 0.829787 (-3550 2675);
PAINT RED (-3550 2675);
DISPLAY INVISIBLE (-3550 2675);
FORCEADD TAP..6
R 2
(-3050 2425);
FORCEPROP 3 LASTPIN (-3100 2425) SIG_NAME GMI_CPU1_G3_CPU0_G1_TX_DP<8>
J 0
(-3090 2435);
DISPLAY 0.659574 (-3090 2435);
PAINT MONO (-3090 2435);
DISPLAY INVISIBLE (-3090 2435);
FORCEPROP 1 LASTPIN (-3100 2425) BN 8
J 2
(-3048 2433);
DISPLAY 0.489362 (-3048 2433);
PAINT MONO (-3048 2433);
FORCEPROP 2 LAST CDS_LIB standard
J 0
(-3050 2425);
DISPLAY INVISIBLE (-3050 2425);
FORCEPROP 2 LAST BOM_COST IO_SLOT
J 0
(-3550 2525);
DISPLAY 0.829787 (-3550 2525);
DISPLAY INVISIBLE (-3550 2525);
FORCEPROP 1 LAST BODY_TYPE PLUMBING
J 2
(-3050 2375);
DISPLAY 0.702128 (-3050 2375);
PAINT GREEN (-3050 2375);
DISPLAY INVISIBLE (-3050 2375);
FORCEPROP 1 LAST HDL_TAP TRUE
J 2
(-3375 2300);
DISPLAY 0.702128 (-3375 2300);
PAINT GREEN (-3375 2300);
DISPLAY INVISIBLE (-3375 2300);
FORCEPROP 1 LAST PATH I247
J 2
(-3048 2425);
DISPLAY 0.872340 (-3048 2425);
PAINT GREEN (-3048 2425);
DISPLAY INVISIBLE (-3048 2425);
FORCEPROP 2 LAST ROOM RISER1
J 0
(-3550 2475);
DISPLAY 0.829787 (-3550 2475);
PAINT RED (-3550 2475);
DISPLAY INVISIBLE (-3550 2475);
FORCEADD TAP..6
R 2
(-3050 2525);
FORCEPROP 3 LASTPIN (-3100 2525) SIG_NAME GMI_CPU1_G3_CPU0_G1_TX_DP<9>
J 0
(-3090 2535);
DISPLAY 0.659574 (-3090 2535);
PAINT MONO (-3090 2535);
DISPLAY INVISIBLE (-3090 2535);
FORCEPROP 1 LASTPIN (-3100 2525) BN 9
J 2
(-3048 2533);
DISPLAY 0.489362 (-3048 2533);
PAINT MONO (-3048 2533);
FORCEPROP 2 LAST CDS_LIB standard
J 0
(-3050 2525);
DISPLAY INVISIBLE (-3050 2525);
FORCEPROP 2 LAST BOM_COST IO_SLOT
J 0
(-3550 2625);
DISPLAY 0.829787 (-3550 2625);
DISPLAY INVISIBLE (-3550 2625);
FORCEPROP 1 LAST BODY_TYPE PLUMBING
J 2
(-3050 2475);
DISPLAY 0.702128 (-3050 2475);
PAINT GREEN (-3050 2475);
DISPLAY INVISIBLE (-3050 2475);
FORCEPROP 1 LAST HDL_TAP TRUE
J 2
(-3375 2400);
DISPLAY 0.702128 (-3375 2400);
PAINT GREEN (-3375 2400);
DISPLAY INVISIBLE (-3375 2400);
FORCEPROP 1 LAST PATH I248
J 2
(-3048 2525);
DISPLAY 0.872340 (-3048 2525);
PAINT GREEN (-3048 2525);
DISPLAY INVISIBLE (-3048 2525);
FORCEPROP 2 LAST ROOM RISER1
J 0
(-3550 2575);
DISPLAY 0.829787 (-3550 2575);
PAINT RED (-3550 2575);
DISPLAY INVISIBLE (-3550 2575);
FORCEADD TAP..6
R 2
(-3050 2325);
FORCEPROP 3 LASTPIN (-3100 2325) SIG_NAME GMI_CPU1_G3_CPU0_G1_TX_DP<7>
J 0
(-3090 2335);
DISPLAY 0.659574 (-3090 2335);
PAINT MONO (-3090 2335);
DISPLAY INVISIBLE (-3090 2335);
FORCEPROP 1 LASTPIN (-3100 2325) BN 7
J 2
(-3048 2333);
DISPLAY 0.489362 (-3048 2333);
PAINT MONO (-3048 2333);
FORCEPROP 2 LAST CDS_LIB standard
J 0
(-3050 2325);
DISPLAY INVISIBLE (-3050 2325);
FORCEPROP 2 LAST BOM_COST IO_SLOT
J 0
(-3550 2425);
DISPLAY 0.829787 (-3550 2425);
DISPLAY INVISIBLE (-3550 2425);
FORCEPROP 1 LAST BODY_TYPE PLUMBING
J 2
(-3050 2275);
DISPLAY 0.702128 (-3050 2275);
PAINT GREEN (-3050 2275);
DISPLAY INVISIBLE (-3050 2275);
FORCEPROP 1 LAST HDL_TAP TRUE
J 2
(-3375 2200);
DISPLAY 0.702128 (-3375 2200);
PAINT GREEN (-3375 2200);
DISPLAY INVISIBLE (-3375 2200);
FORCEPROP 1 LAST PATH I249
J 2
(-3048 2325);
DISPLAY 0.872340 (-3048 2325);
PAINT GREEN (-3048 2325);
DISPLAY INVISIBLE (-3048 2325);
FORCEPROP 2 LAST ROOM RISER1
J 0
(-3550 2375);
DISPLAY 0.829787 (-3550 2375);
PAINT RED (-3550 2375);
DISPLAY INVISIBLE (-3550 2375);
FORCEADD TAP..6
R 2
(-3050 2225);
FORCEPROP 3 LASTPIN (-3100 2225) SIG_NAME GMI_CPU1_G3_CPU0_G1_TX_DP<6>
J 0
(-3090 2235);
DISPLAY 0.659574 (-3090 2235);
PAINT MONO (-3090 2235);
DISPLAY INVISIBLE (-3090 2235);
FORCEPROP 1 LASTPIN (-3100 2225) BN 6
J 2
(-3048 2233);
DISPLAY 0.489362 (-3048 2233);
PAINT MONO (-3048 2233);
FORCEPROP 2 LAST CDS_LIB standard
J 0
(-3050 2225);
DISPLAY INVISIBLE (-3050 2225);
FORCEPROP 2 LAST BOM_COST IO_SLOT
J 0
(-3550 2325);
DISPLAY 0.829787 (-3550 2325);
DISPLAY INVISIBLE (-3550 2325);
FORCEPROP 1 LAST BODY_TYPE PLUMBING
J 2
(-3050 2175);
DISPLAY 0.702128 (-3050 2175);
PAINT GREEN (-3050 2175);
DISPLAY INVISIBLE (-3050 2175);
FORCEPROP 1 LAST HDL_TAP TRUE
J 2
(-3375 2100);
DISPLAY 0.702128 (-3375 2100);
PAINT GREEN (-3375 2100);
DISPLAY INVISIBLE (-3375 2100);
FORCEPROP 1 LAST PATH I250
J 2
(-3048 2225);
DISPLAY 0.872340 (-3048 2225);
PAINT GREEN (-3048 2225);
DISPLAY INVISIBLE (-3048 2225);
FORCEPROP 2 LAST ROOM RISER1
J 0
(-3550 2275);
DISPLAY 0.829787 (-3550 2275);
PAINT RED (-3550 2275);
DISPLAY INVISIBLE (-3550 2275);
FORCEADD TAP..6
R 2
(-3050 2125);
FORCEPROP 3 LASTPIN (-3100 2125) SIG_NAME GMI_CPU1_G3_CPU0_G1_TX_DP<5>
J 0
(-3090 2135);
DISPLAY 0.659574 (-3090 2135);
PAINT MONO (-3090 2135);
DISPLAY INVISIBLE (-3090 2135);
FORCEPROP 1 LASTPIN (-3100 2125) BN 5
J 2
(-3048 2133);
DISPLAY 0.489362 (-3048 2133);
PAINT MONO (-3048 2133);
FORCEPROP 2 LAST CDS_LIB standard
J 0
(-3050 2125);
DISPLAY INVISIBLE (-3050 2125);
FORCEPROP 2 LAST BOM_COST IO_SLOT
J 0
(-3550 2225);
DISPLAY 0.829787 (-3550 2225);
DISPLAY INVISIBLE (-3550 2225);
FORCEPROP 1 LAST BODY_TYPE PLUMBING
J 2
(-3050 2075);
DISPLAY 0.702128 (-3050 2075);
PAINT GREEN (-3050 2075);
DISPLAY INVISIBLE (-3050 2075);
FORCEPROP 1 LAST HDL_TAP TRUE
J 2
(-3375 2000);
DISPLAY 0.702128 (-3375 2000);
PAINT GREEN (-3375 2000);
DISPLAY INVISIBLE (-3375 2000);
FORCEPROP 1 LAST PATH I251
J 2
(-3048 2125);
DISPLAY 0.872340 (-3048 2125);
PAINT GREEN (-3048 2125);
DISPLAY INVISIBLE (-3048 2125);
FORCEPROP 2 LAST ROOM RISER1
J 0
(-3550 2175);
DISPLAY 0.829787 (-3550 2175);
PAINT RED (-3550 2175);
DISPLAY INVISIBLE (-3550 2175);
FORCEADD TAP..6
R 2
(-3050 1825);
FORCEPROP 3 LASTPIN (-3100 1825) SIG_NAME GMI_CPU1_G3_CPU0_G1_TX_DP<2>
J 0
(-3090 1835);
DISPLAY 0.659574 (-3090 1835);
PAINT MONO (-3090 1835);
DISPLAY INVISIBLE (-3090 1835);
FORCEPROP 1 LASTPIN (-3100 1825) BN 2
J 2
(-3048 1833);
DISPLAY 0.489362 (-3048 1833);
PAINT MONO (-3048 1833);
FORCEPROP 2 LAST CDS_LIB standard
J 0
(-3050 1825);
DISPLAY INVISIBLE (-3050 1825);
FORCEPROP 2 LAST BOM_COST IO_SLOT
J 0
(-3550 1925);
DISPLAY 0.829787 (-3550 1925);
DISPLAY INVISIBLE (-3550 1925);
FORCEPROP 1 LAST BODY_TYPE PLUMBING
J 2
(-3050 1775);
DISPLAY 0.702128 (-3050 1775);
PAINT GREEN (-3050 1775);
DISPLAY INVISIBLE (-3050 1775);
FORCEPROP 1 LAST HDL_TAP TRUE
J 2
(-3375 1700);
DISPLAY 0.702128 (-3375 1700);
PAINT GREEN (-3375 1700);
DISPLAY INVISIBLE (-3375 1700);
FORCEPROP 1 LAST PATH I257
J 2
(-3048 1825);
DISPLAY 0.872340 (-3048 1825);
PAINT GREEN (-3048 1825);
DISPLAY INVISIBLE (-3048 1825);
FORCEPROP 2 LAST ROOM RISER1
J 0
(-3550 1875);
DISPLAY 0.829787 (-3550 1875);
PAINT RED (-3550 1875);
DISPLAY INVISIBLE (-3550 1875);
FORCEADD TAP..6
R 2
(-3050 2025);
FORCEPROP 3 LASTPIN (-3100 2025) SIG_NAME GMI_CPU1_G3_CPU0_G1_TX_DP<4>
J 0
(-3090 2035);
DISPLAY 0.659574 (-3090 2035);
PAINT MONO (-3090 2035);
DISPLAY INVISIBLE (-3090 2035);
FORCEPROP 1 LASTPIN (-3100 2025) BN 4
J 2
(-3048 2033);
DISPLAY 0.489362 (-3048 2033);
PAINT MONO (-3048 2033);
FORCEPROP 2 LAST CDS_LIB standard
J 0
(-3050 2025);
DISPLAY INVISIBLE (-3050 2025);
FORCEPROP 2 LAST BOM_COST IO_SLOT
J 0
(-3550 2125);
DISPLAY 0.829787 (-3550 2125);
DISPLAY INVISIBLE (-3550 2125);
FORCEPROP 1 LAST BODY_TYPE PLUMBING
J 2
(-3050 1975);
DISPLAY 0.702128 (-3050 1975);
PAINT GREEN (-3050 1975);
DISPLAY INVISIBLE (-3050 1975);
FORCEPROP 1 LAST HDL_TAP TRUE
J 2
(-3375 1900);
DISPLAY 0.702128 (-3375 1900);
PAINT GREEN (-3375 1900);
DISPLAY INVISIBLE (-3375 1900);
FORCEPROP 1 LAST PATH I258
J 2
(-3048 2025);
DISPLAY 0.872340 (-3048 2025);
PAINT GREEN (-3048 2025);
DISPLAY INVISIBLE (-3048 2025);
FORCEPROP 2 LAST ROOM RISER1
J 0
(-3550 2075);
DISPLAY 0.829787 (-3550 2075);
PAINT RED (-3550 2075);
DISPLAY INVISIBLE (-3550 2075);
FORCEADD TAP..6
R 2
(-3050 1925);
FORCEPROP 3 LASTPIN (-3100 1925) SIG_NAME GMI_CPU1_G3_CPU0_G1_TX_DP<3>
J 0
(-3090 1935);
DISPLAY 0.659574 (-3090 1935);
PAINT MONO (-3090 1935);
DISPLAY INVISIBLE (-3090 1935);
FORCEPROP 1 LASTPIN (-3100 1925) BN 3
J 2
(-3048 1933);
DISPLAY 0.489362 (-3048 1933);
PAINT MONO (-3048 1933);
FORCEPROP 2 LAST CDS_LIB standard
J 0
(-3050 1925);
DISPLAY INVISIBLE (-3050 1925);
FORCEPROP 2 LAST BOM_COST IO_SLOT
J 0
(-3550 2025);
DISPLAY 0.829787 (-3550 2025);
DISPLAY INVISIBLE (-3550 2025);
FORCEPROP 1 LAST BODY_TYPE PLUMBING
J 2
(-3050 1875);
DISPLAY 0.702128 (-3050 1875);
PAINT GREEN (-3050 1875);
DISPLAY INVISIBLE (-3050 1875);
FORCEPROP 1 LAST HDL_TAP TRUE
J 2
(-3375 1800);
DISPLAY 0.702128 (-3375 1800);
PAINT GREEN (-3375 1800);
DISPLAY INVISIBLE (-3375 1800);
FORCEPROP 1 LAST PATH I259
J 2
(-3048 1925);
DISPLAY 0.872340 (-3048 1925);
PAINT GREEN (-3048 1925);
DISPLAY INVISIBLE (-3048 1925);
FORCEPROP 2 LAST ROOM RISER1
J 0
(-3550 1975);
DISPLAY 0.829787 (-3550 1975);
PAINT RED (-3550 1975);
DISPLAY INVISIBLE (-3550 1975);
FORCEADD TAP..6
R 2
(-3050 1725);
FORCEPROP 3 LASTPIN (-3100 1725) SIG_NAME GMI_CPU1_G3_CPU0_G1_TX_DP<1>
J 0
(-3090 1735);
DISPLAY 0.659574 (-3090 1735);
PAINT MONO (-3090 1735);
DISPLAY INVISIBLE (-3090 1735);
FORCEPROP 1 LASTPIN (-3100 1725) BN 1
J 2
(-3048 1733);
DISPLAY 0.489362 (-3048 1733);
PAINT MONO (-3048 1733);
FORCEPROP 2 LAST CDS_LIB standard
J 0
(-3050 1725);
DISPLAY INVISIBLE (-3050 1725);
FORCEPROP 2 LAST BOM_COST IO_SLOT
J 0
(-3550 1825);
DISPLAY 0.829787 (-3550 1825);
DISPLAY INVISIBLE (-3550 1825);
FORCEPROP 1 LAST BODY_TYPE PLUMBING
J 2
(-3050 1675);
DISPLAY 0.702128 (-3050 1675);
PAINT GREEN (-3050 1675);
DISPLAY INVISIBLE (-3050 1675);
FORCEPROP 1 LAST HDL_TAP TRUE
J 2
(-3375 1600);
DISPLAY 0.702128 (-3375 1600);
PAINT GREEN (-3375 1600);
DISPLAY INVISIBLE (-3375 1600);
FORCEPROP 1 LAST PATH I260
J 2
(-3048 1725);
DISPLAY 0.872340 (-3048 1725);
PAINT GREEN (-3048 1725);
DISPLAY INVISIBLE (-3048 1725);
FORCEPROP 2 LAST ROOM RISER1
J 0
(-3550 1775);
DISPLAY 0.829787 (-3550 1775);
PAINT RED (-3550 1775);
DISPLAY INVISIBLE (-3550 1775);
FORCEADD TAP..6
R 2
(-3050 1625);
FORCEPROP 3 LASTPIN (-3100 1625) SIG_NAME GMI_CPU1_G3_CPU0_G1_TX_DP<0>
J 0
(-3090 1635);
DISPLAY 0.659574 (-3090 1635);
PAINT MONO (-3090 1635);
DISPLAY INVISIBLE (-3090 1635);
FORCEPROP 1 LASTPIN (-3100 1625) BN 0
J 2
(-3048 1633);
DISPLAY 0.489362 (-3048 1633);
PAINT MONO (-3048 1633);
FORCEPROP 2 LAST CDS_LIB standard
J 0
(-3050 1625);
DISPLAY INVISIBLE (-3050 1625);
FORCEPROP 2 LAST BOM_COST IO_SLOT
J 0
(-3550 1725);
DISPLAY 0.829787 (-3550 1725);
DISPLAY INVISIBLE (-3550 1725);
FORCEPROP 1 LAST BODY_TYPE PLUMBING
J 2
(-3050 1575);
DISPLAY 0.702128 (-3050 1575);
PAINT GREEN (-3050 1575);
DISPLAY INVISIBLE (-3050 1575);
FORCEPROP 1 LAST HDL_TAP TRUE
J 2
(-3375 1500);
DISPLAY 0.702128 (-3375 1500);
PAINT GREEN (-3375 1500);
DISPLAY INVISIBLE (-3375 1500);
FORCEPROP 1 LAST PATH I261
J 2
(-3048 1625);
DISPLAY 0.872340 (-3048 1625);
PAINT GREEN (-3048 1625);
DISPLAY INVISIBLE (-3048 1625);
FORCEPROP 2 LAST ROOM RISER1
J 0
(-3550 1675);
DISPLAY 0.829787 (-3550 1675);
PAINT RED (-3550 1675);
DISPLAY INVISIBLE (-3550 1675);
FORCEADD TAP..6
(-6500 5800);
FORCEPROP 3 LASTPIN (-6450 5800) SIG_NAME GMI_CPU0_G0_CPU1_G2_TX_DP<15>
J 0
(-6440 5810);
DISPLAY 0.659574 (-6440 5810);
PAINT MONO (-6440 5810);
DISPLAY INVISIBLE (-6440 5810);
FORCEPROP 1 LASTPIN (-6450 5800) BN 15
J 0
(-6502 5808);
DISPLAY 0.489362 (-6502 5808);
PAINT MONO (-6502 5808);
FORCEPROP 2 LAST CDS_LIB mstr_standard
J 0
(-6500 5800);
DISPLAY INVISIBLE (-6500 5800);
FORCEPROP 1 LAST BODY_TYPE PLUMBING
J 0
(-6500 5750);
DISPLAY 0.574468 (-6500 5750);
PAINT GREEN (-6500 5750);
DISPLAY INVISIBLE (-6500 5750);
FORCEPROP 1 LAST HDL_TAP TRUE
J 0
(-6175 5675);
DISPLAY 0.574468 (-6175 5675);
PAINT GREEN (-6175 5675);
DISPLAY INVISIBLE (-6175 5675);
FORCEPROP 1 LAST PATH I262
J 0
(-6502 5800);
DISPLAY 0.872340 (-6502 5800);
PAINT GREEN (-6502 5800);
DISPLAY INVISIBLE (-6502 5800);
FORCEADD TAP..6
(-6500 5700);
FORCEPROP 3 LASTPIN (-6450 5700) SIG_NAME GMI_CPU0_G0_CPU1_G2_TX_DP<14>
J 0
(-6440 5710);
DISPLAY 0.659574 (-6440 5710);
PAINT MONO (-6440 5710);
DISPLAY INVISIBLE (-6440 5710);
FORCEPROP 1 LASTPIN (-6450 5700) BN 14
J 0
(-6502 5708);
DISPLAY 0.489362 (-6502 5708);
PAINT MONO (-6502 5708);
FORCEPROP 2 LAST CDS_LIB mstr_standard
J 0
(-6500 5700);
DISPLAY INVISIBLE (-6500 5700);
FORCEPROP 1 LAST BODY_TYPE PLUMBING
J 0
(-6500 5650);
DISPLAY 0.574468 (-6500 5650);
PAINT GREEN (-6500 5650);
DISPLAY INVISIBLE (-6500 5650);
FORCEPROP 1 LAST HDL_TAP TRUE
J 0
(-6175 5575);
DISPLAY 0.574468 (-6175 5575);
PAINT GREEN (-6175 5575);
DISPLAY INVISIBLE (-6175 5575);
FORCEPROP 1 LAST PATH I263
J 0
(-6502 5700);
DISPLAY 0.872340 (-6502 5700);
PAINT GREEN (-6502 5700);
DISPLAY INVISIBLE (-6502 5700);
FORCEADD TAP..6
(-6500 5600);
FORCEPROP 3 LASTPIN (-6450 5600) SIG_NAME GMI_CPU0_G0_CPU1_G2_TX_DP<13>
J 0
(-6440 5610);
DISPLAY 0.659574 (-6440 5610);
PAINT MONO (-6440 5610);
DISPLAY INVISIBLE (-6440 5610);
FORCEPROP 1 LASTPIN (-6450 5600) BN 13
J 0
(-6502 5608);
DISPLAY 0.489362 (-6502 5608);
PAINT MONO (-6502 5608);
FORCEPROP 2 LAST CDS_LIB mstr_standard
J 0
(-6500 5600);
DISPLAY INVISIBLE (-6500 5600);
FORCEPROP 1 LAST BODY_TYPE PLUMBING
J 0
(-6500 5550);
DISPLAY 0.574468 (-6500 5550);
PAINT GREEN (-6500 5550);
DISPLAY INVISIBLE (-6500 5550);
FORCEPROP 1 LAST HDL_TAP TRUE
J 0
(-6175 5475);
DISPLAY 0.574468 (-6175 5475);
PAINT GREEN (-6175 5475);
DISPLAY INVISIBLE (-6175 5475);
FORCEPROP 1 LAST PATH I266
J 0
(-6502 5600);
DISPLAY 0.872340 (-6502 5600);
PAINT GREEN (-6502 5600);
DISPLAY INVISIBLE (-6502 5600);
FORCEADD TAP..6
(-6500 5500);
FORCEPROP 3 LASTPIN (-6450 5500) SIG_NAME GMI_CPU0_G0_CPU1_G2_TX_DP<12>
J 0
(-6440 5510);
DISPLAY 0.659574 (-6440 5510);
PAINT MONO (-6440 5510);
DISPLAY INVISIBLE (-6440 5510);
FORCEPROP 1 LASTPIN (-6450 5500) BN 12
J 0
(-6502 5508);
DISPLAY 0.489362 (-6502 5508);
PAINT MONO (-6502 5508);
FORCEPROP 2 LAST CDS_LIB standard
J 0
(-6500 5500);
DISPLAY INVISIBLE (-6500 5500);
FORCEPROP 1 LAST BODY_TYPE PLUMBING
J 0
(-6500 5450);
DISPLAY 0.574468 (-6500 5450);
PAINT GREEN (-6500 5450);
DISPLAY INVISIBLE (-6500 5450);
FORCEPROP 1 LAST HDL_TAP TRUE
J 0
(-6175 5375);
DISPLAY 0.574468 (-6175 5375);
PAINT GREEN (-6175 5375);
DISPLAY INVISIBLE (-6175 5375);
FORCEPROP 1 LAST PATH I267
J 0
(-6502 5500);
DISPLAY 0.872340 (-6502 5500);
PAINT GREEN (-6502 5500);
DISPLAY INVISIBLE (-6502 5500);
FORCEADD TAP..6
(-6500 5400);
FORCEPROP 3 LASTPIN (-6450 5400) SIG_NAME GMI_CPU0_G0_CPU1_G2_TX_DP<11>
J 0
(-6440 5410);
DISPLAY 0.659574 (-6440 5410);
PAINT MONO (-6440 5410);
DISPLAY INVISIBLE (-6440 5410);
FORCEPROP 1 LASTPIN (-6450 5400) BN 11
J 0
(-6502 5408);
DISPLAY 0.489362 (-6502 5408);
PAINT MONO (-6502 5408);
FORCEPROP 2 LAST CDS_LIB standard
J 0
(-6500 5400);
DISPLAY INVISIBLE (-6500 5400);
FORCEPROP 1 LAST BODY_TYPE PLUMBING
J 0
(-6500 5350);
DISPLAY 0.574468 (-6500 5350);
PAINT GREEN (-6500 5350);
DISPLAY INVISIBLE (-6500 5350);
FORCEPROP 1 LAST HDL_TAP TRUE
J 0
(-6175 5275);
DISPLAY 0.574468 (-6175 5275);
PAINT GREEN (-6175 5275);
DISPLAY INVISIBLE (-6175 5275);
FORCEPROP 1 LAST PATH I268
J 0
(-6502 5400);
DISPLAY 0.872340 (-6502 5400);
PAINT GREEN (-6502 5400);
DISPLAY INVISIBLE (-6502 5400);
FORCEADD TAP..6
(-6500 5300);
FORCEPROP 3 LASTPIN (-6450 5300) SIG_NAME GMI_CPU0_G0_CPU1_G2_TX_DP<10>
J 0
(-6440 5310);
DISPLAY 0.659574 (-6440 5310);
PAINT MONO (-6440 5310);
DISPLAY INVISIBLE (-6440 5310);
FORCEPROP 1 LASTPIN (-6450 5300) BN 10
J 0
(-6502 5308);
DISPLAY 0.489362 (-6502 5308);
PAINT MONO (-6502 5308);
FORCEPROP 2 LAST CDS_LIB standard
J 0
(-6500 5300);
DISPLAY INVISIBLE (-6500 5300);
FORCEPROP 1 LAST BODY_TYPE PLUMBING
J 0
(-6500 5250);
DISPLAY 0.574468 (-6500 5250);
PAINT GREEN (-6500 5250);
DISPLAY INVISIBLE (-6500 5250);
FORCEPROP 1 LAST HDL_TAP TRUE
J 0
(-6175 5175);
DISPLAY 0.574468 (-6175 5175);
PAINT GREEN (-6175 5175);
DISPLAY INVISIBLE (-6175 5175);
FORCEPROP 1 LAST PATH I271
J 0
(-6502 5300);
DISPLAY 0.872340 (-6502 5300);
PAINT GREEN (-6502 5300);
DISPLAY INVISIBLE (-6502 5300);
FORCEADD TAP..6
(-6500 5200);
FORCEPROP 3 LASTPIN (-6450 5200) SIG_NAME GMI_CPU0_G0_CPU1_G2_TX_DP<9>
J 0
(-6440 5210);
DISPLAY 0.659574 (-6440 5210);
PAINT MONO (-6440 5210);
DISPLAY INVISIBLE (-6440 5210);
FORCEPROP 1 LASTPIN (-6450 5200) BN 9
J 0
(-6502 5208);
DISPLAY 0.489362 (-6502 5208);
PAINT MONO (-6502 5208);
FORCEPROP 2 LAST CDS_LIB standard
J 0
(-6500 5200);
DISPLAY INVISIBLE (-6500 5200);
FORCEPROP 1 LAST BODY_TYPE PLUMBING
J 0
(-6500 5150);
DISPLAY 0.574468 (-6500 5150);
PAINT GREEN (-6500 5150);
DISPLAY INVISIBLE (-6500 5150);
FORCEPROP 1 LAST HDL_TAP TRUE
J 0
(-6175 5075);
DISPLAY 0.574468 (-6175 5075);
PAINT GREEN (-6175 5075);
DISPLAY INVISIBLE (-6175 5075);
FORCEPROP 1 LAST PATH I272
J 0
(-6502 5200);
DISPLAY 0.872340 (-6502 5200);
PAINT GREEN (-6502 5200);
DISPLAY INVISIBLE (-6502 5200);
FORCEADD TAP..6
(-6500 5100);
FORCEPROP 3 LASTPIN (-6450 5100) SIG_NAME GMI_CPU0_G0_CPU1_G2_TX_DP<8>
J 0
(-6440 5110);
DISPLAY 0.659574 (-6440 5110);
PAINT MONO (-6440 5110);
DISPLAY INVISIBLE (-6440 5110);
FORCEPROP 1 LASTPIN (-6450 5100) BN 8
J 0
(-6502 5108);
DISPLAY 0.489362 (-6502 5108);
PAINT MONO (-6502 5108);
FORCEPROP 2 LAST CDS_LIB standard
J 0
(-6500 5100);
DISPLAY INVISIBLE (-6500 5100);
FORCEPROP 1 LAST BODY_TYPE PLUMBING
J 0
(-6500 5050);
DISPLAY 0.574468 (-6500 5050);
PAINT GREEN (-6500 5050);
DISPLAY INVISIBLE (-6500 5050);
FORCEPROP 1 LAST HDL_TAP TRUE
J 0
(-6175 4975);
DISPLAY 0.574468 (-6175 4975);
PAINT GREEN (-6175 4975);
DISPLAY INVISIBLE (-6175 4975);
FORCEPROP 1 LAST PATH I276
J 0
(-6502 5100);
DISPLAY 0.872340 (-6502 5100);
PAINT GREEN (-6502 5100);
DISPLAY INVISIBLE (-6502 5100);
FORCEADD TAP..6
(-6500 4900);
FORCEPROP 3 LASTPIN (-6450 4900) SIG_NAME GMI_CPU0_G0_CPU1_G2_TX_DP<6>
J 0
(-6440 4910);
DISPLAY 0.659574 (-6440 4910);
PAINT MONO (-6440 4910);
DISPLAY INVISIBLE (-6440 4910);
FORCEPROP 1 LASTPIN (-6450 4900) BN 6
J 0
(-6502 4908);
DISPLAY 0.489362 (-6502 4908);
PAINT MONO (-6502 4908);
FORCEPROP 2 LAST CDS_LIB standard
J 0
(-6500 4900);
DISPLAY INVISIBLE (-6500 4900);
FORCEPROP 1 LAST BODY_TYPE PLUMBING
J 0
(-6500 4850);
DISPLAY 0.574468 (-6500 4850);
PAINT GREEN (-6500 4850);
DISPLAY INVISIBLE (-6500 4850);
FORCEPROP 1 LAST HDL_TAP TRUE
J 0
(-6175 4775);
DISPLAY 0.574468 (-6175 4775);
PAINT GREEN (-6175 4775);
DISPLAY INVISIBLE (-6175 4775);
FORCEPROP 1 LAST PATH I277
J 0
(-6502 4900);
DISPLAY 0.872340 (-6502 4900);
PAINT GREEN (-6502 4900);
DISPLAY INVISIBLE (-6502 4900);
FORCEADD TAP..6
(-6500 5000);
FORCEPROP 3 LASTPIN (-6450 5000) SIG_NAME GMI_CPU0_G0_CPU1_G2_TX_DP<7>
J 0
(-6440 5010);
DISPLAY 0.659574 (-6440 5010);
PAINT MONO (-6440 5010);
DISPLAY INVISIBLE (-6440 5010);
FORCEPROP 1 LASTPIN (-6450 5000) BN 7
J 0
(-6502 5008);
DISPLAY 0.489362 (-6502 5008);
PAINT MONO (-6502 5008);
FORCEPROP 2 LAST CDS_LIB standard
J 0
(-6500 5000);
DISPLAY INVISIBLE (-6500 5000);
FORCEPROP 1 LAST BODY_TYPE PLUMBING
J 0
(-6500 4950);
DISPLAY 0.574468 (-6500 4950);
PAINT GREEN (-6500 4950);
DISPLAY INVISIBLE (-6500 4950);
FORCEPROP 1 LAST HDL_TAP TRUE
J 0
(-6175 4875);
DISPLAY 0.574468 (-6175 4875);
PAINT GREEN (-6175 4875);
DISPLAY INVISIBLE (-6175 4875);
FORCEPROP 1 LAST PATH I278
J 0
(-6502 5000);
DISPLAY 0.872340 (-6502 5000);
PAINT GREEN (-6502 5000);
DISPLAY INVISIBLE (-6502 5000);
FORCEADD TAP..6
(-6500 4800);
FORCEPROP 3 LASTPIN (-6450 4800) SIG_NAME GMI_CPU0_G0_CPU1_G2_TX_DP<5>
J 0
(-6440 4810);
DISPLAY 0.659574 (-6440 4810);
PAINT MONO (-6440 4810);
DISPLAY INVISIBLE (-6440 4810);
FORCEPROP 1 LASTPIN (-6450 4800) BN 5
J 0
(-6502 4808);
DISPLAY 0.489362 (-6502 4808);
PAINT MONO (-6502 4808);
FORCEPROP 2 LAST CDS_LIB standard
J 0
(-6500 4800);
DISPLAY INVISIBLE (-6500 4800);
FORCEPROP 1 LAST BODY_TYPE PLUMBING
J 0
(-6500 4750);
DISPLAY 0.574468 (-6500 4750);
PAINT GREEN (-6500 4750);
DISPLAY INVISIBLE (-6500 4750);
FORCEPROP 1 LAST HDL_TAP TRUE
J 0
(-6175 4675);
DISPLAY 0.574468 (-6175 4675);
PAINT GREEN (-6175 4675);
DISPLAY INVISIBLE (-6175 4675);
FORCEPROP 1 LAST PATH I281
J 0
(-6502 4800);
DISPLAY 0.872340 (-6502 4800);
PAINT GREEN (-6502 4800);
DISPLAY INVISIBLE (-6502 4800);
FORCEADD TAP..6
(-6500 4700);
FORCEPROP 3 LASTPIN (-6450 4700) SIG_NAME GMI_CPU0_G0_CPU1_G2_TX_DP<4>
J 0
(-6440 4710);
DISPLAY 0.659574 (-6440 4710);
PAINT MONO (-6440 4710);
DISPLAY INVISIBLE (-6440 4710);
FORCEPROP 1 LASTPIN (-6450 4700) BN 4
J 0
(-6502 4708);
DISPLAY 0.489362 (-6502 4708);
PAINT MONO (-6502 4708);
FORCEPROP 2 LAST CDS_LIB standard
J 0
(-6500 4700);
DISPLAY INVISIBLE (-6500 4700);
FORCEPROP 1 LAST BODY_TYPE PLUMBING
J 0
(-6500 4650);
DISPLAY 0.574468 (-6500 4650);
PAINT GREEN (-6500 4650);
DISPLAY INVISIBLE (-6500 4650);
FORCEPROP 1 LAST HDL_TAP TRUE
J 0
(-6175 4575);
DISPLAY 0.574468 (-6175 4575);
PAINT GREEN (-6175 4575);
DISPLAY INVISIBLE (-6175 4575);
FORCEPROP 1 LAST PATH I282
J 0
(-6502 4700);
DISPLAY 0.872340 (-6502 4700);
PAINT GREEN (-6502 4700);
DISPLAY INVISIBLE (-6502 4700);
FORCEADD TAP..6
(-6500 4600);
FORCEPROP 3 LASTPIN (-6450 4600) SIG_NAME GMI_CPU0_G0_CPU1_G2_TX_DP<3>
J 0
(-6440 4610);
DISPLAY 0.659574 (-6440 4610);
PAINT MONO (-6440 4610);
DISPLAY INVISIBLE (-6440 4610);
FORCEPROP 1 LASTPIN (-6450 4600) BN 3
J 0
(-6502 4608);
DISPLAY 0.489362 (-6502 4608);
PAINT MONO (-6502 4608);
FORCEPROP 2 LAST CDS_LIB standard
J 0
(-6500 4600);
DISPLAY INVISIBLE (-6500 4600);
FORCEPROP 1 LAST BODY_TYPE PLUMBING
J 0
(-6500 4550);
DISPLAY 0.574468 (-6500 4550);
PAINT GREEN (-6500 4550);
DISPLAY INVISIBLE (-6500 4550);
FORCEPROP 1 LAST HDL_TAP TRUE
J 0
(-6175 4475);
DISPLAY 0.574468 (-6175 4475);
PAINT GREEN (-6175 4475);
DISPLAY INVISIBLE (-6175 4475);
FORCEPROP 1 LAST PATH I286
J 0
(-6502 4600);
DISPLAY 0.872340 (-6502 4600);
PAINT GREEN (-6502 4600);
DISPLAY INVISIBLE (-6502 4600);
FORCEADD TAP..6
(-6500 4400);
FORCEPROP 3 LASTPIN (-6450 4400) SIG_NAME GMI_CPU0_G0_CPU1_G2_TX_DP<1>
J 0
(-6440 4410);
DISPLAY 0.659574 (-6440 4410);
PAINT MONO (-6440 4410);
DISPLAY INVISIBLE (-6440 4410);
FORCEPROP 1 LASTPIN (-6450 4400) BN 1
J 0
(-6502 4408);
DISPLAY 0.489362 (-6502 4408);
PAINT MONO (-6502 4408);
FORCEPROP 2 LAST CDS_LIB standard
J 0
(-6500 4400);
DISPLAY INVISIBLE (-6500 4400);
FORCEPROP 1 LAST BODY_TYPE PLUMBING
J 0
(-6500 4350);
DISPLAY 0.574468 (-6500 4350);
PAINT GREEN (-6500 4350);
DISPLAY INVISIBLE (-6500 4350);
FORCEPROP 1 LAST HDL_TAP TRUE
J 0
(-6175 4275);
DISPLAY 0.574468 (-6175 4275);
PAINT GREEN (-6175 4275);
DISPLAY INVISIBLE (-6175 4275);
FORCEPROP 1 LAST PATH I287
J 0
(-6502 4400);
DISPLAY 0.872340 (-6502 4400);
PAINT GREEN (-6502 4400);
DISPLAY INVISIBLE (-6502 4400);
FORCEADD TAP..6
(-6500 4500);
FORCEPROP 3 LASTPIN (-6450 4500) SIG_NAME GMI_CPU0_G0_CPU1_G2_TX_DP<2>
J 0
(-6440 4510);
DISPLAY 0.659574 (-6440 4510);
PAINT MONO (-6440 4510);
DISPLAY INVISIBLE (-6440 4510);
FORCEPROP 1 LASTPIN (-6450 4500) BN 2
J 0
(-6502 4508);
DISPLAY 0.489362 (-6502 4508);
PAINT MONO (-6502 4508);
FORCEPROP 2 LAST CDS_LIB standard
J 0
(-6500 4500);
DISPLAY INVISIBLE (-6500 4500);
FORCEPROP 1 LAST BODY_TYPE PLUMBING
J 0
(-6500 4450);
DISPLAY 0.574468 (-6500 4450);
PAINT GREEN (-6500 4450);
DISPLAY INVISIBLE (-6500 4450);
FORCEPROP 1 LAST HDL_TAP TRUE
J 0
(-6175 4375);
DISPLAY 0.574468 (-6175 4375);
PAINT GREEN (-6175 4375);
DISPLAY INVISIBLE (-6175 4375);
FORCEPROP 1 LAST PATH I288
J 0
(-6502 4500);
DISPLAY 0.872340 (-6502 4500);
PAINT GREEN (-6502 4500);
DISPLAY INVISIBLE (-6502 4500);
FORCEADD TAP..6
(-6500 4300);
FORCEPROP 3 LASTPIN (-6450 4300) SIG_NAME GMI_CPU0_G0_CPU1_G2_TX_DP<0>
J 0
(-6440 4310);
DISPLAY 0.659574 (-6440 4310);
PAINT MONO (-6440 4310);
DISPLAY INVISIBLE (-6440 4310);
FORCEPROP 1 LASTPIN (-6450 4300) BN 0
J 0
(-6502 4308);
DISPLAY 0.489362 (-6502 4308);
PAINT MONO (-6502 4308);
FORCEPROP 2 LAST CDS_LIB standard
J 0
(-6500 4300);
DISPLAY INVISIBLE (-6500 4300);
FORCEPROP 1 LAST BODY_TYPE PLUMBING
J 0
(-6500 4250);
DISPLAY 0.574468 (-6500 4250);
PAINT GREEN (-6500 4250);
DISPLAY INVISIBLE (-6500 4250);
FORCEPROP 1 LAST HDL_TAP TRUE
J 0
(-6175 4175);
DISPLAY 0.574468 (-6175 4175);
PAINT GREEN (-6175 4175);
DISPLAY INVISIBLE (-6175 4175);
FORCEPROP 1 LAST PATH I291
J 0
(-6502 4300);
DISPLAY 0.872340 (-6502 4300);
PAINT GREEN (-6502 4300);
DISPLAY INVISIBLE (-6502 4300);
FORCEADD OFFPAGE..1
(-7700 6025);
FORCEPROP 2 LAST $XR0 22 
J 0
(-7951 6025);
DISPLAY 0.638298 (-7951 6025);
PAINT MONO (-7951 6025);
FORCEPROP 2 LAST CDS_LIB standard
J 0
(-7700 6025);
DISPLAY INVISIBLE (-7700 6025);
FORCEPROP 1 LAST OFFPAGE TRUE
J 0
(-7375 5900);
DISPLAY 0.872340 (-7375 5900);
PAINT GREEN (-7375 5900);
DISPLAY INVISIBLE (-7375 5900);
FORCEPROP 1 LAST COMMENT_BODY TRUE
J 0
(-7575 5925);
DISPLAY 0.872340 (-7575 5925);
PAINT GREEN (-7575 5925);
DISPLAY INVISIBLE (-7575 5925);
FORCEPROP 2 LAST PATH I295
J 0
(-7900 6075);
DISPLAY 1.021277 (-7900 6075);
DISPLAY INVISIBLE (-7900 6075);
FORCEADD TAP..6
(-6475 3125);
FORCEPROP 3 LASTPIN (-6425 3125) SIG_NAME GMI_CPU0_G1_CPU1_G3_TX_DP<15>
J 0
(-6415 3135);
DISPLAY 0.659574 (-6415 3135);
PAINT MONO (-6415 3135);
DISPLAY INVISIBLE (-6415 3135);
FORCEPROP 1 LASTPIN (-6425 3125) BN 15
J 0
(-6477 3133);
DISPLAY 0.489362 (-6477 3133);
PAINT MONO (-6477 3133);
FORCEPROP 2 LAST CDS_LIB standard
J 0
(-6475 3125);
DISPLAY INVISIBLE (-6475 3125);
FORCEPROP 1 LAST BODY_TYPE PLUMBING
J 0
(-6475 3075);
DISPLAY 0.574468 (-6475 3075);
PAINT GREEN (-6475 3075);
DISPLAY INVISIBLE (-6475 3075);
FORCEPROP 1 LAST HDL_TAP TRUE
J 0
(-6150 3000);
DISPLAY 0.574468 (-6150 3000);
PAINT GREEN (-6150 3000);
DISPLAY INVISIBLE (-6150 3000);
FORCEPROP 1 LAST PATH I296
J 0
(-6477 3125);
DISPLAY 0.872340 (-6477 3125);
PAINT GREEN (-6477 3125);
DISPLAY INVISIBLE (-6477 3125);
FORCEADD TAP..6
(-6475 2925);
FORCEPROP 3 LASTPIN (-6425 2925) SIG_NAME GMI_CPU0_G1_CPU1_G3_TX_DP<13>
J 0
(-6415 2935);
DISPLAY 0.659574 (-6415 2935);
PAINT MONO (-6415 2935);
DISPLAY INVISIBLE (-6415 2935);
FORCEPROP 1 LASTPIN (-6425 2925) BN 13
J 0
(-6477 2933);
DISPLAY 0.489362 (-6477 2933);
PAINT MONO (-6477 2933);
FORCEPROP 2 LAST CDS_LIB standard
J 0
(-6475 2925);
DISPLAY INVISIBLE (-6475 2925);
FORCEPROP 1 LAST BODY_TYPE PLUMBING
J 0
(-6475 2875);
DISPLAY 0.574468 (-6475 2875);
PAINT GREEN (-6475 2875);
DISPLAY INVISIBLE (-6475 2875);
FORCEPROP 1 LAST HDL_TAP TRUE
J 0
(-6150 2800);
DISPLAY 0.574468 (-6150 2800);
PAINT GREEN (-6150 2800);
DISPLAY INVISIBLE (-6150 2800);
FORCEPROP 1 LAST PATH I298
J 0
(-6477 2925);
DISPLAY 0.872340 (-6477 2925);
PAINT GREEN (-6477 2925);
DISPLAY INVISIBLE (-6477 2925);
FORCEADD TAP..6
(-6475 3025);
FORCEPROP 3 LASTPIN (-6425 3025) SIG_NAME GMI_CPU0_G1_CPU1_G3_TX_DP<14>
J 0
(-6415 3035);
DISPLAY 0.659574 (-6415 3035);
PAINT MONO (-6415 3035);
DISPLAY INVISIBLE (-6415 3035);
FORCEPROP 1 LASTPIN (-6425 3025) BN 14
J 0
(-6477 3033);
DISPLAY 0.489362 (-6477 3033);
PAINT MONO (-6477 3033);
FORCEPROP 2 LAST CDS_LIB standard
J 0
(-6475 3025);
DISPLAY INVISIBLE (-6475 3025);
FORCEPROP 1 LAST BODY_TYPE PLUMBING
J 0
(-6475 2975);
DISPLAY 0.574468 (-6475 2975);
PAINT GREEN (-6475 2975);
DISPLAY INVISIBLE (-6475 2975);
FORCEPROP 1 LAST HDL_TAP TRUE
J 0
(-6150 2900);
DISPLAY 0.574468 (-6150 2900);
PAINT GREEN (-6150 2900);
DISPLAY INVISIBLE (-6150 2900);
FORCEPROP 1 LAST PATH I299
J 0
(-6477 3025);
DISPLAY 0.872340 (-6477 3025);
PAINT GREEN (-6477 3025);
DISPLAY INVISIBLE (-6477 3025);
FORCEADD TAP..6
(-6475 2825);
FORCEPROP 3 LASTPIN (-6425 2825) SIG_NAME GMI_CPU0_G1_CPU1_G3_TX_DP<12>
J 0
(-6415 2835);
DISPLAY 0.659574 (-6415 2835);
PAINT MONO (-6415 2835);
DISPLAY INVISIBLE (-6415 2835);
FORCEPROP 1 LASTPIN (-6425 2825) BN 12
J 0
(-6477 2833);
DISPLAY 0.489362 (-6477 2833);
PAINT MONO (-6477 2833);
FORCEPROP 2 LAST CDS_LIB standard
J 0
(-6475 2825);
DISPLAY INVISIBLE (-6475 2825);
FORCEPROP 1 LAST BODY_TYPE PLUMBING
J 0
(-6475 2775);
DISPLAY 0.574468 (-6475 2775);
PAINT GREEN (-6475 2775);
DISPLAY INVISIBLE (-6475 2775);
FORCEPROP 1 LAST HDL_TAP TRUE
J 0
(-6150 2700);
DISPLAY 0.574468 (-6150 2700);
PAINT GREEN (-6150 2700);
DISPLAY INVISIBLE (-6150 2700);
FORCEPROP 1 LAST PATH I300
J 0
(-6477 2825);
DISPLAY 0.872340 (-6477 2825);
PAINT GREEN (-6477 2825);
DISPLAY INVISIBLE (-6477 2825);
FORCEADD TAP..6
(-6475 2725);
FORCEPROP 3 LASTPIN (-6425 2725) SIG_NAME GMI_CPU0_G1_CPU1_G3_TX_DP<11>
J 0
(-6415 2735);
DISPLAY 0.659574 (-6415 2735);
PAINT MONO (-6415 2735);
DISPLAY INVISIBLE (-6415 2735);
FORCEPROP 1 LASTPIN (-6425 2725) BN 11
J 0
(-6477 2733);
DISPLAY 0.489362 (-6477 2733);
PAINT MONO (-6477 2733);
FORCEPROP 2 LAST CDS_LIB standard
J 0
(-6475 2725);
DISPLAY INVISIBLE (-6475 2725);
FORCEPROP 1 LAST BODY_TYPE PLUMBING
J 0
(-6475 2675);
DISPLAY 0.574468 (-6475 2675);
PAINT GREEN (-6475 2675);
DISPLAY INVISIBLE (-6475 2675);
FORCEPROP 1 LAST HDL_TAP TRUE
J 0
(-6150 2600);
DISPLAY 0.574468 (-6150 2600);
PAINT GREEN (-6150 2600);
DISPLAY INVISIBLE (-6150 2600);
FORCEPROP 1 LAST PATH I303
J 0
(-6477 2725);
DISPLAY 0.872340 (-6477 2725);
PAINT GREEN (-6477 2725);
DISPLAY INVISIBLE (-6477 2725);
FORCEADD TAP..6
(-6475 2625);
FORCEPROP 3 LASTPIN (-6425 2625) SIG_NAME GMI_CPU0_G1_CPU1_G3_TX_DP<10>
J 0
(-6415 2635);
DISPLAY 0.659574 (-6415 2635);
PAINT MONO (-6415 2635);
DISPLAY INVISIBLE (-6415 2635);
FORCEPROP 1 LASTPIN (-6425 2625) BN 10
J 0
(-6477 2633);
DISPLAY 0.489362 (-6477 2633);
PAINT MONO (-6477 2633);
FORCEPROP 2 LAST CDS_LIB standard
J 0
(-6475 2625);
DISPLAY INVISIBLE (-6475 2625);
FORCEPROP 1 LAST BODY_TYPE PLUMBING
J 0
(-6475 2575);
DISPLAY 0.574468 (-6475 2575);
PAINT GREEN (-6475 2575);
DISPLAY INVISIBLE (-6475 2575);
FORCEPROP 1 LAST HDL_TAP TRUE
J 0
(-6150 2500);
DISPLAY 0.574468 (-6150 2500);
PAINT GREEN (-6150 2500);
DISPLAY INVISIBLE (-6150 2500);
FORCEPROP 1 LAST PATH I304
J 0
(-6477 2625);
DISPLAY 0.872340 (-6477 2625);
PAINT GREEN (-6477 2625);
DISPLAY INVISIBLE (-6477 2625);
FORCEADD TAP..6
(-6475 2425);
FORCEPROP 3 LASTPIN (-6425 2425) SIG_NAME GMI_CPU0_G1_CPU1_G3_TX_DP<8>
J 0
(-6415 2435);
DISPLAY 0.659574 (-6415 2435);
PAINT MONO (-6415 2435);
DISPLAY INVISIBLE (-6415 2435);
FORCEPROP 1 LASTPIN (-6425 2425) BN 8
J 0
(-6477 2433);
DISPLAY 0.489362 (-6477 2433);
PAINT MONO (-6477 2433);
FORCEPROP 2 LAST CDS_LIB standard
J 0
(-6475 2425);
DISPLAY INVISIBLE (-6475 2425);
FORCEPROP 1 LAST BODY_TYPE PLUMBING
J 0
(-6475 2375);
DISPLAY 0.574468 (-6475 2375);
PAINT GREEN (-6475 2375);
DISPLAY INVISIBLE (-6475 2375);
FORCEPROP 1 LAST HDL_TAP TRUE
J 0
(-6150 2300);
DISPLAY 0.574468 (-6150 2300);
PAINT GREEN (-6150 2300);
DISPLAY INVISIBLE (-6150 2300);
FORCEPROP 1 LAST PATH I308
J 0
(-6477 2425);
DISPLAY 0.872340 (-6477 2425);
PAINT GREEN (-6477 2425);
DISPLAY INVISIBLE (-6477 2425);
FORCEADD TAP..6
(-6475 2525);
FORCEPROP 3 LASTPIN (-6425 2525) SIG_NAME GMI_CPU0_G1_CPU1_G3_TX_DP<9>
J 0
(-6415 2535);
DISPLAY 0.659574 (-6415 2535);
PAINT MONO (-6415 2535);
DISPLAY INVISIBLE (-6415 2535);
FORCEPROP 1 LASTPIN (-6425 2525) BN 9
J 0
(-6477 2533);
DISPLAY 0.489362 (-6477 2533);
PAINT MONO (-6477 2533);
FORCEPROP 2 LAST CDS_LIB standard
J 0
(-6475 2525);
DISPLAY INVISIBLE (-6475 2525);
FORCEPROP 1 LAST BODY_TYPE PLUMBING
J 0
(-6475 2475);
DISPLAY 0.574468 (-6475 2475);
PAINT GREEN (-6475 2475);
DISPLAY INVISIBLE (-6475 2475);
FORCEPROP 1 LAST HDL_TAP TRUE
J 0
(-6150 2400);
DISPLAY 0.574468 (-6150 2400);
PAINT GREEN (-6150 2400);
DISPLAY INVISIBLE (-6150 2400);
FORCEPROP 1 LAST PATH I309
J 0
(-6477 2525);
DISPLAY 0.872340 (-6477 2525);
PAINT GREEN (-6477 2525);
DISPLAY INVISIBLE (-6477 2525);
FORCEADD TAP..6
(-6475 2325);
FORCEPROP 3 LASTPIN (-6425 2325) SIG_NAME GMI_CPU0_G1_CPU1_G3_TX_DP<7>
J 0
(-6415 2335);
DISPLAY 0.659574 (-6415 2335);
PAINT MONO (-6415 2335);
DISPLAY INVISIBLE (-6415 2335);
FORCEPROP 1 LASTPIN (-6425 2325) BN 7
J 0
(-6477 2333);
DISPLAY 0.489362 (-6477 2333);
PAINT MONO (-6477 2333);
FORCEPROP 2 LAST CDS_LIB standard
J 0
(-6475 2325);
DISPLAY INVISIBLE (-6475 2325);
FORCEPROP 1 LAST BODY_TYPE PLUMBING
J 0
(-6475 2275);
DISPLAY 0.574468 (-6475 2275);
PAINT GREEN (-6475 2275);
DISPLAY INVISIBLE (-6475 2275);
FORCEPROP 1 LAST HDL_TAP TRUE
J 0
(-6150 2200);
DISPLAY 0.574468 (-6150 2200);
PAINT GREEN (-6150 2200);
DISPLAY INVISIBLE (-6150 2200);
FORCEPROP 1 LAST PATH I310
J 0
(-6477 2325);
DISPLAY 0.872340 (-6477 2325);
PAINT GREEN (-6477 2325);
DISPLAY INVISIBLE (-6477 2325);
FORCEADD TAP..6
(-6475 2225);
FORCEPROP 3 LASTPIN (-6425 2225) SIG_NAME GMI_CPU0_G1_CPU1_G3_TX_DP<6>
J 0
(-6415 2235);
DISPLAY 0.659574 (-6415 2235);
PAINT MONO (-6415 2235);
DISPLAY INVISIBLE (-6415 2235);
FORCEPROP 1 LASTPIN (-6425 2225) BN 6
J 0
(-6477 2233);
DISPLAY 0.489362 (-6477 2233);
PAINT MONO (-6477 2233);
FORCEPROP 2 LAST CDS_LIB standard
J 0
(-6475 2225);
DISPLAY INVISIBLE (-6475 2225);
FORCEPROP 1 LAST BODY_TYPE PLUMBING
J 0
(-6475 2175);
DISPLAY 0.574468 (-6475 2175);
PAINT GREEN (-6475 2175);
DISPLAY INVISIBLE (-6475 2175);
FORCEPROP 1 LAST HDL_TAP TRUE
J 0
(-6150 2100);
DISPLAY 0.574468 (-6150 2100);
PAINT GREEN (-6150 2100);
DISPLAY INVISIBLE (-6150 2100);
FORCEPROP 1 LAST PATH I313
J 0
(-6477 2225);
DISPLAY 0.872340 (-6477 2225);
PAINT GREEN (-6477 2225);
DISPLAY INVISIBLE (-6477 2225);
FORCEADD TAP..6
(-6475 2125);
FORCEPROP 3 LASTPIN (-6425 2125) SIG_NAME GMI_CPU0_G1_CPU1_G3_TX_DP<5>
J 0
(-6415 2135);
DISPLAY 0.659574 (-6415 2135);
PAINT MONO (-6415 2135);
DISPLAY INVISIBLE (-6415 2135);
FORCEPROP 1 LASTPIN (-6425 2125) BN 5
J 0
(-6477 2133);
DISPLAY 0.489362 (-6477 2133);
PAINT MONO (-6477 2133);
FORCEPROP 2 LAST CDS_LIB standard
J 0
(-6475 2125);
DISPLAY INVISIBLE (-6475 2125);
FORCEPROP 1 LAST BODY_TYPE PLUMBING
J 0
(-6475 2075);
DISPLAY 0.574468 (-6475 2075);
PAINT GREEN (-6475 2075);
DISPLAY INVISIBLE (-6475 2075);
FORCEPROP 1 LAST HDL_TAP TRUE
J 0
(-6150 2000);
DISPLAY 0.574468 (-6150 2000);
PAINT GREEN (-6150 2000);
DISPLAY INVISIBLE (-6150 2000);
FORCEPROP 1 LAST PATH I314
J 0
(-6477 2125);
DISPLAY 0.872340 (-6477 2125);
PAINT GREEN (-6477 2125);
DISPLAY INVISIBLE (-6477 2125);
FORCEADD OFFPAGE..1
(-7575 3350);
FORCEPROP 2 LASTPIN (-7525 3350) SIG_NAME GMI_CPU0_G1_CPU1_G3_TX_DP<15:0>
J 0
(-7535 3360);
DISPLAY 0.489362 (-7535 3360);
FORCEPROP 2 LAST $XR0 22 
J 0
(-7826 3350);
DISPLAY 0.638298 (-7826 3350);
PAINT MONO (-7826 3350);
FORCEPROP 2 LAST CDS_LIB standard
J 0
(-7575 3350);
DISPLAY INVISIBLE (-7575 3350);
FORCEPROP 1 LAST OFFPAGE TRUE
J 0
(-7250 3225);
DISPLAY 0.872340 (-7250 3225);
PAINT GREEN (-7250 3225);
DISPLAY INVISIBLE (-7250 3225);
FORCEPROP 1 LAST COMMENT_BODY TRUE
J 0
(-7450 3250);
DISPLAY 0.872340 (-7450 3250);
PAINT GREEN (-7450 3250);
DISPLAY INVISIBLE (-7450 3250);
FORCEPROP 2 LAST PATH I318
J 0
(-7825 3400);
DISPLAY 1.021277 (-7825 3400);
DISPLAY INVISIBLE (-7825 3400);
FORCEADD TAP..6
(-6475 2025);
FORCEPROP 3 LASTPIN (-6425 2025) SIG_NAME GMI_CPU0_G1_CPU1_G3_TX_DP<4>
J 0
(-6415 2035);
DISPLAY 0.659574 (-6415 2035);
PAINT MONO (-6415 2035);
DISPLAY INVISIBLE (-6415 2035);
FORCEPROP 1 LASTPIN (-6425 2025) BN 4
J 0
(-6477 2033);
DISPLAY 0.489362 (-6477 2033);
PAINT MONO (-6477 2033);
FORCEPROP 2 LAST CDS_LIB standard
J 0
(-6475 2025);
DISPLAY INVISIBLE (-6475 2025);
FORCEPROP 1 LAST BODY_TYPE PLUMBING
J 0
(-6475 1975);
DISPLAY 0.574468 (-6475 1975);
PAINT GREEN (-6475 1975);
DISPLAY INVISIBLE (-6475 1975);
FORCEPROP 1 LAST HDL_TAP TRUE
J 0
(-6150 1900);
DISPLAY 0.574468 (-6150 1900);
PAINT GREEN (-6150 1900);
DISPLAY INVISIBLE (-6150 1900);
FORCEPROP 1 LAST PATH I320
J 0
(-6477 2025);
DISPLAY 0.872340 (-6477 2025);
PAINT GREEN (-6477 2025);
DISPLAY INVISIBLE (-6477 2025);
FORCEADD TAP..6
(-6475 1925);
FORCEPROP 3 LASTPIN (-6425 1925) SIG_NAME GMI_CPU0_G1_CPU1_G3_TX_DP<3>
J 0
(-6415 1935);
DISPLAY 0.659574 (-6415 1935);
PAINT MONO (-6415 1935);
DISPLAY INVISIBLE (-6415 1935);
FORCEPROP 1 LASTPIN (-6425 1925) BN 3
J 0
(-6477 1933);
DISPLAY 0.489362 (-6477 1933);
PAINT MONO (-6477 1933);
FORCEPROP 2 LAST CDS_LIB standard
J 0
(-6475 1925);
DISPLAY INVISIBLE (-6475 1925);
FORCEPROP 1 LAST BODY_TYPE PLUMBING
J 0
(-6475 1875);
DISPLAY 0.574468 (-6475 1875);
PAINT GREEN (-6475 1875);
DISPLAY INVISIBLE (-6475 1875);
FORCEPROP 1 LAST HDL_TAP TRUE
J 0
(-6150 1800);
DISPLAY 0.574468 (-6150 1800);
PAINT GREEN (-6150 1800);
DISPLAY INVISIBLE (-6150 1800);
FORCEPROP 1 LAST PATH I321
J 0
(-6477 1925);
DISPLAY 0.872340 (-6477 1925);
PAINT GREEN (-6477 1925);
DISPLAY INVISIBLE (-6477 1925);
FORCEADD TAP..6
(-6475 1825);
FORCEPROP 3 LASTPIN (-6425 1825) SIG_NAME GMI_CPU0_G1_CPU1_G3_TX_DP<2>
J 0
(-6415 1835);
DISPLAY 0.659574 (-6415 1835);
PAINT MONO (-6415 1835);
DISPLAY INVISIBLE (-6415 1835);
FORCEPROP 1 LASTPIN (-6425 1825) BN 2
J 0
(-6477 1833);
DISPLAY 0.489362 (-6477 1833);
PAINT MONO (-6477 1833);
FORCEPROP 2 LAST CDS_LIB standard
J 0
(-6475 1825);
DISPLAY INVISIBLE (-6475 1825);
FORCEPROP 1 LAST BODY_TYPE PLUMBING
J 0
(-6475 1775);
DISPLAY 0.574468 (-6475 1775);
PAINT GREEN (-6475 1775);
DISPLAY INVISIBLE (-6475 1775);
FORCEPROP 1 LAST HDL_TAP TRUE
J 0
(-6150 1700);
DISPLAY 0.574468 (-6150 1700);
PAINT GREEN (-6150 1700);
DISPLAY INVISIBLE (-6150 1700);
FORCEPROP 1 LAST PATH I322
J 0
(-6477 1825);
DISPLAY 0.872340 (-6477 1825);
PAINT GREEN (-6477 1825);
DISPLAY INVISIBLE (-6477 1825);
FORCEADD TAP..6
(-6475 1725);
FORCEPROP 3 LASTPIN (-6425 1725) SIG_NAME GMI_CPU0_G1_CPU1_G3_TX_DP<1>
J 0
(-6415 1735);
DISPLAY 0.659574 (-6415 1735);
PAINT MONO (-6415 1735);
DISPLAY INVISIBLE (-6415 1735);
FORCEPROP 1 LASTPIN (-6425 1725) BN 1
J 0
(-6477 1733);
DISPLAY 0.489362 (-6477 1733);
PAINT MONO (-6477 1733);
FORCEPROP 2 LAST CDS_LIB standard
J 0
(-6475 1725);
DISPLAY INVISIBLE (-6475 1725);
FORCEPROP 1 LAST BODY_TYPE PLUMBING
J 0
(-6475 1675);
DISPLAY 0.574468 (-6475 1675);
PAINT GREEN (-6475 1675);
DISPLAY INVISIBLE (-6475 1675);
FORCEPROP 1 LAST HDL_TAP TRUE
J 0
(-6150 1600);
DISPLAY 0.574468 (-6150 1600);
PAINT GREEN (-6150 1600);
DISPLAY INVISIBLE (-6150 1600);
FORCEPROP 1 LAST PATH I325
J 0
(-6477 1725);
DISPLAY 0.872340 (-6477 1725);
PAINT GREEN (-6477 1725);
DISPLAY INVISIBLE (-6477 1725);
FORCEADD TAP..6
(-6475 1625);
FORCEPROP 3 LASTPIN (-6425 1625) SIG_NAME GMI_CPU0_G1_CPU1_G3_TX_DP<0>
J 0
(-6415 1635);
DISPLAY 0.659574 (-6415 1635);
PAINT MONO (-6415 1635);
DISPLAY INVISIBLE (-6415 1635);
FORCEPROP 1 LASTPIN (-6425 1625) BN 0
J 0
(-6477 1633);
DISPLAY 0.489362 (-6477 1633);
PAINT MONO (-6477 1633);
FORCEPROP 2 LAST CDS_LIB standard
J 0
(-6475 1625);
DISPLAY INVISIBLE (-6475 1625);
FORCEPROP 1 LAST BODY_TYPE PLUMBING
J 0
(-6475 1575);
DISPLAY 0.574468 (-6475 1575);
PAINT GREEN (-6475 1575);
DISPLAY INVISIBLE (-6475 1575);
FORCEPROP 1 LAST HDL_TAP TRUE
J 0
(-6150 1500);
DISPLAY 0.574468 (-6150 1500);
PAINT GREEN (-6150 1500);
DISPLAY INVISIBLE (-6150 1500);
FORCEPROP 1 LAST PATH I327
J 0
(-6477 1625);
DISPLAY 0.872340 (-6477 1625);
PAINT GREEN (-6477 1625);
DISPLAY INVISIBLE (-6477 1625);
FORCEADD TAP..6
(-6650 5750);
FORCEPROP 3 LASTPIN (-6600 5750) SIG_NAME GMI_CPU0_G0_CPU1_G2_TX_DN<15>
J 0
(-6590 5760);
DISPLAY 0.659574 (-6590 5760);
PAINT MONO (-6590 5760);
DISPLAY INVISIBLE (-6590 5760);
FORCEPROP 1 LASTPIN (-6600 5750) BN 15
J 0
(-6652 5758);
DISPLAY 0.489362 (-6652 5758);
PAINT MONO (-6652 5758);
FORCEPROP 2 LAST CDS_LIB mstr_standard
J 0
(-6650 5750);
DISPLAY INVISIBLE (-6650 5750);
FORCEPROP 1 LAST BODY_TYPE PLUMBING
J 0
(-6650 5700);
DISPLAY 0.574468 (-6650 5700);
PAINT GREEN (-6650 5700);
DISPLAY INVISIBLE (-6650 5700);
FORCEPROP 1 LAST HDL_TAP TRUE
J 0
(-6325 5625);
DISPLAY 0.574468 (-6325 5625);
PAINT GREEN (-6325 5625);
DISPLAY INVISIBLE (-6325 5625);
FORCEPROP 1 LAST PATH I398
J 0
(-6652 5750);
DISPLAY 0.872340 (-6652 5750);
PAINT GREEN (-6652 5750);
DISPLAY INVISIBLE (-6652 5750);
FORCEADD TAP..6
(-6650 5650);
FORCEPROP 3 LASTPIN (-6600 5650) SIG_NAME GMI_CPU0_G0_CPU1_G2_TX_DN<14>
J 0
(-6590 5660);
DISPLAY 0.659574 (-6590 5660);
PAINT MONO (-6590 5660);
DISPLAY INVISIBLE (-6590 5660);
FORCEPROP 1 LASTPIN (-6600 5650) BN 14
J 0
(-6652 5658);
DISPLAY 0.489362 (-6652 5658);
PAINT MONO (-6652 5658);
FORCEPROP 2 LAST CDS_LIB mstr_standard
J 0
(-6650 5650);
DISPLAY INVISIBLE (-6650 5650);
FORCEPROP 1 LAST BODY_TYPE PLUMBING
J 0
(-6650 5600);
DISPLAY 0.574468 (-6650 5600);
PAINT GREEN (-6650 5600);
DISPLAY INVISIBLE (-6650 5600);
FORCEPROP 1 LAST HDL_TAP TRUE
J 0
(-6325 5525);
DISPLAY 0.574468 (-6325 5525);
PAINT GREEN (-6325 5525);
DISPLAY INVISIBLE (-6325 5525);
FORCEPROP 1 LAST PATH I399
J 0
(-6652 5650);
DISPLAY 0.872340 (-6652 5650);
PAINT GREEN (-6652 5650);
DISPLAY INVISIBLE (-6652 5650);
FORCEADD TAP..6
(-6650 5450);
FORCEPROP 3 LASTPIN (-6600 5450) SIG_NAME GMI_CPU0_G0_CPU1_G2_TX_DN<12>
J 0
(-6590 5460);
DISPLAY 0.659574 (-6590 5460);
PAINT MONO (-6590 5460);
DISPLAY INVISIBLE (-6590 5460);
FORCEPROP 1 LASTPIN (-6600 5450) BN 12
J 0
(-6652 5458);
DISPLAY 0.489362 (-6652 5458);
PAINT MONO (-6652 5458);
FORCEPROP 2 LAST CDS_LIB standard
J 0
(-6650 5450);
DISPLAY INVISIBLE (-6650 5450);
FORCEPROP 1 LAST BODY_TYPE PLUMBING
J 0
(-6650 5400);
DISPLAY 0.574468 (-6650 5400);
PAINT GREEN (-6650 5400);
DISPLAY INVISIBLE (-6650 5400);
FORCEPROP 1 LAST HDL_TAP TRUE
J 0
(-6325 5325);
DISPLAY 0.574468 (-6325 5325);
PAINT GREEN (-6325 5325);
DISPLAY INVISIBLE (-6325 5325);
FORCEPROP 1 LAST PATH I400
J 0
(-6652 5450);
DISPLAY 0.872340 (-6652 5450);
PAINT GREEN (-6652 5450);
DISPLAY INVISIBLE (-6652 5450);
FORCEADD TAP..6
(-6650 5550);
FORCEPROP 3 LASTPIN (-6600 5550) SIG_NAME GMI_CPU0_G0_CPU1_G2_TX_DN<13>
J 0
(-6590 5560);
DISPLAY 0.659574 (-6590 5560);
PAINT MONO (-6590 5560);
DISPLAY INVISIBLE (-6590 5560);
FORCEPROP 1 LASTPIN (-6600 5550) BN 13
J 0
(-6652 5558);
DISPLAY 0.489362 (-6652 5558);
PAINT MONO (-6652 5558);
FORCEPROP 2 LAST CDS_LIB standard
J 0
(-6650 5550);
DISPLAY INVISIBLE (-6650 5550);
FORCEPROP 1 LAST BODY_TYPE PLUMBING
J 0
(-6650 5500);
DISPLAY 0.574468 (-6650 5500);
PAINT GREEN (-6650 5500);
DISPLAY INVISIBLE (-6650 5500);
FORCEPROP 1 LAST HDL_TAP TRUE
J 0
(-6325 5425);
DISPLAY 0.574468 (-6325 5425);
PAINT GREEN (-6325 5425);
DISPLAY INVISIBLE (-6325 5425);
FORCEPROP 1 LAST PATH I401
J 0
(-6652 5550);
DISPLAY 0.872340 (-6652 5550);
PAINT GREEN (-6652 5550);
DISPLAY INVISIBLE (-6652 5550);
FORCEADD TAP..6
(-6650 5150);
FORCEPROP 3 LASTPIN (-6600 5150) SIG_NAME GMI_CPU0_G0_CPU1_G2_TX_DN<9>
J 0
(-6590 5160);
DISPLAY 0.659574 (-6590 5160);
PAINT MONO (-6590 5160);
DISPLAY INVISIBLE (-6590 5160);
FORCEPROP 1 LASTPIN (-6600 5150) BN 9
J 0
(-6652 5158);
DISPLAY 0.489362 (-6652 5158);
PAINT MONO (-6652 5158);
FORCEPROP 2 LAST CDS_LIB standard
J 0
(-6650 5150);
DISPLAY INVISIBLE (-6650 5150);
FORCEPROP 1 LAST BODY_TYPE PLUMBING
J 0
(-6650 5100);
DISPLAY 0.574468 (-6650 5100);
PAINT GREEN (-6650 5100);
DISPLAY INVISIBLE (-6650 5100);
FORCEPROP 1 LAST HDL_TAP TRUE
J 0
(-6325 5025);
DISPLAY 0.574468 (-6325 5025);
PAINT GREEN (-6325 5025);
DISPLAY INVISIBLE (-6325 5025);
FORCEPROP 1 LAST PATH I402
J 0
(-6652 5150);
DISPLAY 0.872340 (-6652 5150);
PAINT GREEN (-6652 5150);
DISPLAY INVISIBLE (-6652 5150);
FORCEADD TAP..6
(-6650 5350);
FORCEPROP 3 LASTPIN (-6600 5350) SIG_NAME GMI_CPU0_G0_CPU1_G2_TX_DN<11>
J 0
(-6590 5360);
DISPLAY 0.659574 (-6590 5360);
PAINT MONO (-6590 5360);
DISPLAY INVISIBLE (-6590 5360);
FORCEPROP 1 LASTPIN (-6600 5350) BN 11
J 0
(-6652 5358);
DISPLAY 0.489362 (-6652 5358);
PAINT MONO (-6652 5358);
FORCEPROP 2 LAST CDS_LIB standard
J 0
(-6650 5350);
DISPLAY INVISIBLE (-6650 5350);
FORCEPROP 1 LAST BODY_TYPE PLUMBING
J 0
(-6650 5300);
DISPLAY 0.574468 (-6650 5300);
PAINT GREEN (-6650 5300);
DISPLAY INVISIBLE (-6650 5300);
FORCEPROP 1 LAST HDL_TAP TRUE
J 0
(-6325 5225);
DISPLAY 0.574468 (-6325 5225);
PAINT GREEN (-6325 5225);
DISPLAY INVISIBLE (-6325 5225);
FORCEPROP 1 LAST PATH I403
J 0
(-6652 5350);
DISPLAY 0.872340 (-6652 5350);
PAINT GREEN (-6652 5350);
DISPLAY INVISIBLE (-6652 5350);
FORCEADD TAP..6
(-6650 5250);
FORCEPROP 3 LASTPIN (-6600 5250) SIG_NAME GMI_CPU0_G0_CPU1_G2_TX_DN<10>
J 0
(-6590 5260);
DISPLAY 0.659574 (-6590 5260);
PAINT MONO (-6590 5260);
DISPLAY INVISIBLE (-6590 5260);
FORCEPROP 1 LASTPIN (-6600 5250) BN 10
J 0
(-6652 5258);
DISPLAY 0.489362 (-6652 5258);
PAINT MONO (-6652 5258);
FORCEPROP 2 LAST CDS_LIB standard
J 0
(-6650 5250);
DISPLAY INVISIBLE (-6650 5250);
FORCEPROP 1 LAST BODY_TYPE PLUMBING
J 0
(-6650 5200);
DISPLAY 0.574468 (-6650 5200);
PAINT GREEN (-6650 5200);
DISPLAY INVISIBLE (-6650 5200);
FORCEPROP 1 LAST HDL_TAP TRUE
J 0
(-6325 5125);
DISPLAY 0.574468 (-6325 5125);
PAINT GREEN (-6325 5125);
DISPLAY INVISIBLE (-6325 5125);
FORCEPROP 1 LAST PATH I404
J 0
(-6652 5250);
DISPLAY 0.872340 (-6652 5250);
PAINT GREEN (-6652 5250);
DISPLAY INVISIBLE (-6652 5250);
FORCEADD TAP..6
(-6650 4950);
FORCEPROP 3 LASTPIN (-6600 4950) SIG_NAME GMI_CPU0_G0_CPU1_G2_TX_DN<7>
J 0
(-6590 4960);
DISPLAY 0.659574 (-6590 4960);
PAINT MONO (-6590 4960);
DISPLAY INVISIBLE (-6590 4960);
FORCEPROP 1 LASTPIN (-6600 4950) BN 7
J 0
(-6652 4958);
DISPLAY 0.489362 (-6652 4958);
PAINT MONO (-6652 4958);
FORCEPROP 2 LAST CDS_LIB standard
J 0
(-6650 4950);
DISPLAY INVISIBLE (-6650 4950);
FORCEPROP 1 LAST BODY_TYPE PLUMBING
J 0
(-6650 4900);
DISPLAY 0.574468 (-6650 4900);
PAINT GREEN (-6650 4900);
DISPLAY INVISIBLE (-6650 4900);
FORCEPROP 1 LAST HDL_TAP TRUE
J 0
(-6325 4825);
DISPLAY 0.574468 (-6325 4825);
PAINT GREEN (-6325 4825);
DISPLAY INVISIBLE (-6325 4825);
FORCEPROP 1 LAST PATH I405
J 0
(-6652 4950);
DISPLAY 0.872340 (-6652 4950);
PAINT GREEN (-6652 4950);
DISPLAY INVISIBLE (-6652 4950);
FORCEADD TAP..6
(-6650 5050);
FORCEPROP 3 LASTPIN (-6600 5050) SIG_NAME GMI_CPU0_G0_CPU1_G2_TX_DN<8>
J 0
(-6590 5060);
DISPLAY 0.659574 (-6590 5060);
PAINT MONO (-6590 5060);
DISPLAY INVISIBLE (-6590 5060);
FORCEPROP 1 LASTPIN (-6600 5050) BN 8
J 0
(-6652 5058);
DISPLAY 0.489362 (-6652 5058);
PAINT MONO (-6652 5058);
FORCEPROP 2 LAST CDS_LIB standard
J 0
(-6650 5050);
DISPLAY INVISIBLE (-6650 5050);
FORCEPROP 1 LAST BODY_TYPE PLUMBING
J 0
(-6650 5000);
DISPLAY 0.574468 (-6650 5000);
PAINT GREEN (-6650 5000);
DISPLAY INVISIBLE (-6650 5000);
FORCEPROP 1 LAST HDL_TAP TRUE
J 0
(-6325 4925);
DISPLAY 0.574468 (-6325 4925);
PAINT GREEN (-6325 4925);
DISPLAY INVISIBLE (-6325 4925);
FORCEPROP 1 LAST PATH I406
J 0
(-6652 5050);
DISPLAY 0.872340 (-6652 5050);
PAINT GREEN (-6652 5050);
DISPLAY INVISIBLE (-6652 5050);
FORCEADD TAP..6
(-6650 4850);
FORCEPROP 3 LASTPIN (-6600 4850) SIG_NAME GMI_CPU0_G0_CPU1_G2_TX_DN<6>
J 0
(-6590 4860);
DISPLAY 0.659574 (-6590 4860);
PAINT MONO (-6590 4860);
DISPLAY INVISIBLE (-6590 4860);
FORCEPROP 1 LASTPIN (-6600 4850) BN 6
J 0
(-6652 4858);
DISPLAY 0.489362 (-6652 4858);
PAINT MONO (-6652 4858);
FORCEPROP 2 LAST CDS_LIB standard
J 0
(-6650 4850);
DISPLAY INVISIBLE (-6650 4850);
FORCEPROP 1 LAST BODY_TYPE PLUMBING
J 0
(-6650 4800);
DISPLAY 0.574468 (-6650 4800);
PAINT GREEN (-6650 4800);
DISPLAY INVISIBLE (-6650 4800);
FORCEPROP 1 LAST HDL_TAP TRUE
J 0
(-6325 4725);
DISPLAY 0.574468 (-6325 4725);
PAINT GREEN (-6325 4725);
DISPLAY INVISIBLE (-6325 4725);
FORCEPROP 1 LAST PATH I407
J 0
(-6652 4850);
DISPLAY 0.872340 (-6652 4850);
PAINT GREEN (-6652 4850);
DISPLAY INVISIBLE (-6652 4850);
FORCEADD TAP..6
(-6650 4650);
FORCEPROP 3 LASTPIN (-6600 4650) SIG_NAME GMI_CPU0_G0_CPU1_G2_TX_DN<4>
J 0
(-6590 4660);
DISPLAY 0.659574 (-6590 4660);
PAINT MONO (-6590 4660);
DISPLAY INVISIBLE (-6590 4660);
FORCEPROP 1 LASTPIN (-6600 4650) BN 4
J 0
(-6652 4658);
DISPLAY 0.489362 (-6652 4658);
PAINT MONO (-6652 4658);
FORCEPROP 2 LAST CDS_LIB standard
J 0
(-6650 4650);
DISPLAY INVISIBLE (-6650 4650);
FORCEPROP 1 LAST BODY_TYPE PLUMBING
J 0
(-6650 4600);
DISPLAY 0.574468 (-6650 4600);
PAINT GREEN (-6650 4600);
DISPLAY INVISIBLE (-6650 4600);
FORCEPROP 1 LAST HDL_TAP TRUE
J 0
(-6325 4525);
DISPLAY 0.574468 (-6325 4525);
PAINT GREEN (-6325 4525);
DISPLAY INVISIBLE (-6325 4525);
FORCEPROP 1 LAST PATH I408
J 0
(-6652 4650);
DISPLAY 0.872340 (-6652 4650);
PAINT GREEN (-6652 4650);
DISPLAY INVISIBLE (-6652 4650);
FORCEADD TAP..6
(-6650 4750);
FORCEPROP 3 LASTPIN (-6600 4750) SIG_NAME GMI_CPU0_G0_CPU1_G2_TX_DN<5>
J 0
(-6590 4760);
DISPLAY 0.659574 (-6590 4760);
PAINT MONO (-6590 4760);
DISPLAY INVISIBLE (-6590 4760);
FORCEPROP 1 LASTPIN (-6600 4750) BN 5
J 0
(-6652 4758);
DISPLAY 0.489362 (-6652 4758);
PAINT MONO (-6652 4758);
FORCEPROP 2 LAST CDS_LIB standard
J 0
(-6650 4750);
DISPLAY INVISIBLE (-6650 4750);
FORCEPROP 1 LAST BODY_TYPE PLUMBING
J 0
(-6650 4700);
DISPLAY 0.574468 (-6650 4700);
PAINT GREEN (-6650 4700);
DISPLAY INVISIBLE (-6650 4700);
FORCEPROP 1 LAST HDL_TAP TRUE
J 0
(-6325 4625);
DISPLAY 0.574468 (-6325 4625);
PAINT GREEN (-6325 4625);
DISPLAY INVISIBLE (-6325 4625);
FORCEPROP 1 LAST PATH I409
J 0
(-6652 4750);
DISPLAY 0.872340 (-6652 4750);
PAINT GREEN (-6652 4750);
DISPLAY INVISIBLE (-6652 4750);
FORCEADD TAP..6
(-6650 4450);
FORCEPROP 3 LASTPIN (-6600 4450) SIG_NAME GMI_CPU0_G0_CPU1_G2_TX_DN<2>
J 0
(-6590 4460);
DISPLAY 0.659574 (-6590 4460);
PAINT MONO (-6590 4460);
DISPLAY INVISIBLE (-6590 4460);
FORCEPROP 1 LASTPIN (-6600 4450) BN 2
J 0
(-6652 4458);
DISPLAY 0.489362 (-6652 4458);
PAINT MONO (-6652 4458);
FORCEPROP 2 LAST CDS_LIB standard
J 0
(-6650 4450);
DISPLAY INVISIBLE (-6650 4450);
FORCEPROP 1 LAST BODY_TYPE PLUMBING
J 0
(-6650 4400);
DISPLAY 0.574468 (-6650 4400);
PAINT GREEN (-6650 4400);
DISPLAY INVISIBLE (-6650 4400);
FORCEPROP 1 LAST HDL_TAP TRUE
J 0
(-6325 4325);
DISPLAY 0.574468 (-6325 4325);
PAINT GREEN (-6325 4325);
DISPLAY INVISIBLE (-6325 4325);
FORCEPROP 1 LAST PATH I410
J 0
(-6652 4450);
DISPLAY 0.872340 (-6652 4450);
PAINT GREEN (-6652 4450);
DISPLAY INVISIBLE (-6652 4450);
FORCEADD TAP..6
(-6650 4550);
FORCEPROP 3 LASTPIN (-6600 4550) SIG_NAME GMI_CPU0_G0_CPU1_G2_TX_DN<3>
J 0
(-6590 4560);
DISPLAY 0.659574 (-6590 4560);
PAINT MONO (-6590 4560);
DISPLAY INVISIBLE (-6590 4560);
FORCEPROP 1 LASTPIN (-6600 4550) BN 3
J 0
(-6652 4558);
DISPLAY 0.489362 (-6652 4558);
PAINT MONO (-6652 4558);
FORCEPROP 2 LAST CDS_LIB standard
J 0
(-6650 4550);
DISPLAY INVISIBLE (-6650 4550);
FORCEPROP 1 LAST BODY_TYPE PLUMBING
J 0
(-6650 4500);
DISPLAY 0.574468 (-6650 4500);
PAINT GREEN (-6650 4500);
DISPLAY INVISIBLE (-6650 4500);
FORCEPROP 1 LAST HDL_TAP TRUE
J 0
(-6325 4425);
DISPLAY 0.574468 (-6325 4425);
PAINT GREEN (-6325 4425);
DISPLAY INVISIBLE (-6325 4425);
FORCEPROP 1 LAST PATH I411
J 0
(-6652 4550);
DISPLAY 0.872340 (-6652 4550);
PAINT GREEN (-6652 4550);
DISPLAY INVISIBLE (-6652 4550);
FORCEADD TAP..6
(-6650 4350);
FORCEPROP 3 LASTPIN (-6600 4350) SIG_NAME GMI_CPU0_G0_CPU1_G2_TX_DN<1>
J 0
(-6590 4360);
DISPLAY 0.659574 (-6590 4360);
PAINT MONO (-6590 4360);
DISPLAY INVISIBLE (-6590 4360);
FORCEPROP 1 LASTPIN (-6600 4350) BN 1
J 0
(-6652 4358);
DISPLAY 0.489362 (-6652 4358);
PAINT MONO (-6652 4358);
FORCEPROP 2 LAST CDS_LIB standard
J 0
(-6650 4350);
DISPLAY INVISIBLE (-6650 4350);
FORCEPROP 1 LAST BODY_TYPE PLUMBING
J 0
(-6650 4300);
DISPLAY 0.574468 (-6650 4300);
PAINT GREEN (-6650 4300);
DISPLAY INVISIBLE (-6650 4300);
FORCEPROP 1 LAST HDL_TAP TRUE
J 0
(-6325 4225);
DISPLAY 0.574468 (-6325 4225);
PAINT GREEN (-6325 4225);
DISPLAY INVISIBLE (-6325 4225);
FORCEPROP 1 LAST PATH I412
J 0
(-6652 4350);
DISPLAY 0.872340 (-6652 4350);
PAINT GREEN (-6652 4350);
DISPLAY INVISIBLE (-6652 4350);
FORCEADD TAP..6
(-6650 4250);
FORCEPROP 3 LASTPIN (-6600 4250) SIG_NAME GMI_CPU0_G0_CPU1_G2_TX_DN<0>
J 0
(-6590 4260);
DISPLAY 0.659574 (-6590 4260);
PAINT MONO (-6590 4260);
DISPLAY INVISIBLE (-6590 4260);
FORCEPROP 1 LASTPIN (-6600 4250) BN 0
J 0
(-6652 4258);
DISPLAY 0.489362 (-6652 4258);
PAINT MONO (-6652 4258);
FORCEPROP 2 LAST CDS_LIB standard
J 0
(-6650 4250);
DISPLAY INVISIBLE (-6650 4250);
FORCEPROP 1 LAST BODY_TYPE PLUMBING
J 0
(-6650 4200);
DISPLAY 0.574468 (-6650 4200);
PAINT GREEN (-6650 4200);
DISPLAY INVISIBLE (-6650 4200);
FORCEPROP 1 LAST HDL_TAP TRUE
J 0
(-6325 4125);
DISPLAY 0.574468 (-6325 4125);
PAINT GREEN (-6325 4125);
DISPLAY INVISIBLE (-6325 4125);
FORCEPROP 1 LAST PATH I413
J 0
(-6652 4250);
DISPLAY 0.872340 (-6652 4250);
PAINT GREEN (-6652 4250);
DISPLAY INVISIBLE (-6652 4250);
FORCEADD OFFPAGE..1
(-7700 5975);
FORCEPROP 2 LAST $XR0 22 
J 0
(-7951 5975);
DISPLAY 0.638298 (-7951 5975);
PAINT MONO (-7951 5975);
FORCEPROP 2 LAST CDS_LIB standard
J 0
(-7700 5975);
DISPLAY INVISIBLE (-7700 5975);
FORCEPROP 1 LAST OFFPAGE TRUE
J 0
(-7375 5850);
DISPLAY 0.872340 (-7375 5850);
PAINT GREEN (-7375 5850);
DISPLAY INVISIBLE (-7375 5850);
FORCEPROP 1 LAST COMMENT_BODY TRUE
J 0
(-7575 5875);
DISPLAY 0.872340 (-7575 5875);
PAINT GREEN (-7575 5875);
DISPLAY INVISIBLE (-7575 5875);
FORCEPROP 2 LAST PATH I414
J 0
(-7950 6025);
DISPLAY 1.021277 (-7950 6025);
DISPLAY INVISIBLE (-7950 6025);
FORCEADD OFFPAGE..2
(-1800 5975);
FORCEPROP 2 LAST $XR0 22 
J 0
(-1611 5975);
DISPLAY 0.638298 (-1611 5975);
PAINT MONO (-1611 5975);
FORCEPROP 2 LAST CDS_LIB standard
J 0
(-1800 5975);
DISPLAY INVISIBLE (-1800 5975);
FORCEPROP 1 LAST OFFPAGE TRUE
J 0
(-1475 5850);
DISPLAY 0.872340 (-1475 5850);
PAINT GREEN (-1475 5850);
DISPLAY INVISIBLE (-1475 5850);
FORCEPROP 1 LAST COMMENT_BODY TRUE
J 0
(-1845 5880);
DISPLAY 0.872340 (-1845 5880);
PAINT GREEN (-1845 5880);
DISPLAY INVISIBLE (-1845 5880);
FORCEPROP 2 LAST PATH I415
J 0
(-1600 6025);
DISPLAY 1.021277 (-1600 6025);
DISPLAY INVISIBLE (-1600 6025);
FORCEADD TAP..6
R 2
(-2925 5750);
FORCEPROP 3 LASTPIN (-2975 5750) SIG_NAME GMI_CPU1_G2_CPU0_G0_TX_DN<15>
J 0
(-2965 5760);
DISPLAY 0.659574 (-2965 5760);
PAINT MONO (-2965 5760);
DISPLAY INVISIBLE (-2965 5760);
FORCEPROP 1 LASTPIN (-2975 5750) BN 15
J 2
(-2923 5758);
DISPLAY 0.489362 (-2923 5758);
PAINT MONO (-2923 5758);
FORCEPROP 2 LAST CDS_LIB mstr_standard
J 0
(-2925 5750);
DISPLAY INVISIBLE (-2925 5750);
FORCEPROP 2 LAST BOM_COST IO_SLOT
J 0
(-3425 5850);
DISPLAY 0.829787 (-3425 5850);
DISPLAY INVISIBLE (-3425 5850);
FORCEPROP 1 LAST BODY_TYPE PLUMBING
J 2
(-2925 5700);
DISPLAY 0.702128 (-2925 5700);
PAINT GREEN (-2925 5700);
DISPLAY INVISIBLE (-2925 5700);
FORCEPROP 1 LAST HDL_TAP TRUE
J 2
(-3250 5625);
DISPLAY 0.702128 (-3250 5625);
PAINT GREEN (-3250 5625);
DISPLAY INVISIBLE (-3250 5625);
FORCEPROP 1 LAST PATH I416
J 2
(-2923 5750);
DISPLAY 0.872340 (-2923 5750);
PAINT GREEN (-2923 5750);
DISPLAY INVISIBLE (-2923 5750);
FORCEPROP 2 LAST ROOM RISER1
J 0
(-3425 5800);
DISPLAY 0.829787 (-3425 5800);
PAINT RED (-3425 5800);
DISPLAY INVISIBLE (-3425 5800);
FORCEADD TAP..6
R 2
(-2925 5650);
FORCEPROP 3 LASTPIN (-2975 5650) SIG_NAME GMI_CPU1_G2_CPU0_G0_TX_DN<14>
J 0
(-2965 5660);
DISPLAY 0.659574 (-2965 5660);
PAINT MONO (-2965 5660);
DISPLAY INVISIBLE (-2965 5660);
FORCEPROP 1 LASTPIN (-2975 5650) BN 14
J 2
(-2923 5658);
DISPLAY 0.489362 (-2923 5658);
PAINT MONO (-2923 5658);
FORCEPROP 2 LAST BOM_COST IO_SLOT
J 0
(-3425 5750);
DISPLAY 0.829787 (-3425 5750);
DISPLAY INVISIBLE (-3425 5750);
FORCEPROP 2 LAST CDS_LIB mstr_standard
J 0
(-2925 5650);
DISPLAY INVISIBLE (-2925 5650);
FORCEPROP 1 LAST BODY_TYPE PLUMBING
J 2
(-2925 5600);
DISPLAY 0.702128 (-2925 5600);
PAINT GREEN (-2925 5600);
DISPLAY INVISIBLE (-2925 5600);
FORCEPROP 1 LAST HDL_TAP TRUE
J 2
(-3250 5525);
DISPLAY 0.702128 (-3250 5525);
PAINT GREEN (-3250 5525);
DISPLAY INVISIBLE (-3250 5525);
FORCEPROP 1 LAST PATH I417
J 2
(-2923 5650);
DISPLAY 0.872340 (-2923 5650);
PAINT GREEN (-2923 5650);
DISPLAY INVISIBLE (-2923 5650);
FORCEPROP 2 LAST ROOM RISER1
J 0
(-3425 5700);
DISPLAY 0.829787 (-3425 5700);
PAINT RED (-3425 5700);
DISPLAY INVISIBLE (-3425 5700);
FORCEADD TAP..6
R 2
(-2925 5250);
FORCEPROP 3 LASTPIN (-2975 5250) SIG_NAME GMI_CPU1_G2_CPU0_G0_TX_DN<10>
J 0
(-2965 5260);
DISPLAY 0.659574 (-2965 5260);
PAINT MONO (-2965 5260);
DISPLAY INVISIBLE (-2965 5260);
FORCEPROP 1 LASTPIN (-2975 5250) BN 10
J 2
(-2923 5258);
DISPLAY 0.489362 (-2923 5258);
PAINT MONO (-2923 5258);
FORCEPROP 2 LAST BOM_COST IO_SLOT
J 0
(-3425 5350);
DISPLAY 0.829787 (-3425 5350);
DISPLAY INVISIBLE (-3425 5350);
FORCEPROP 2 LAST CDS_LIB standard
J 0
(-2925 5250);
DISPLAY INVISIBLE (-2925 5250);
FORCEPROP 1 LAST BODY_TYPE PLUMBING
J 2
(-2925 5200);
DISPLAY 0.702128 (-2925 5200);
PAINT GREEN (-2925 5200);
DISPLAY INVISIBLE (-2925 5200);
FORCEPROP 1 LAST HDL_TAP TRUE
J 2
(-3250 5125);
DISPLAY 0.702128 (-3250 5125);
PAINT GREEN (-3250 5125);
DISPLAY INVISIBLE (-3250 5125);
FORCEPROP 1 LAST PATH I418
J 2
(-2923 5250);
DISPLAY 0.872340 (-2923 5250);
PAINT GREEN (-2923 5250);
DISPLAY INVISIBLE (-2923 5250);
FORCEPROP 2 LAST ROOM RISER1
J 0
(-3425 5300);
DISPLAY 0.829787 (-3425 5300);
PAINT RED (-3425 5300);
DISPLAY INVISIBLE (-3425 5300);
FORCEADD TAP..6
R 2
(-2925 5150);
FORCEPROP 3 LASTPIN (-2975 5150) SIG_NAME GMI_CPU1_G2_CPU0_G0_TX_DN<9>
J 0
(-2965 5160);
DISPLAY 0.659574 (-2965 5160);
PAINT MONO (-2965 5160);
DISPLAY INVISIBLE (-2965 5160);
FORCEPROP 1 LASTPIN (-2975 5150) BN 9
J 2
(-2923 5158);
DISPLAY 0.489362 (-2923 5158);
PAINT MONO (-2923 5158);
FORCEPROP 2 LAST BOM_COST IO_SLOT
J 0
(-3425 5250);
DISPLAY 0.829787 (-3425 5250);
DISPLAY INVISIBLE (-3425 5250);
FORCEPROP 2 LAST CDS_LIB standard
J 0
(-2925 5150);
DISPLAY INVISIBLE (-2925 5150);
FORCEPROP 1 LAST BODY_TYPE PLUMBING
J 2
(-2925 5100);
DISPLAY 0.702128 (-2925 5100);
PAINT GREEN (-2925 5100);
DISPLAY INVISIBLE (-2925 5100);
FORCEPROP 1 LAST HDL_TAP TRUE
J 2
(-3250 5025);
DISPLAY 0.702128 (-3250 5025);
PAINT GREEN (-3250 5025);
DISPLAY INVISIBLE (-3250 5025);
FORCEPROP 1 LAST PATH I419
J 2
(-2923 5150);
DISPLAY 0.872340 (-2923 5150);
PAINT GREEN (-2923 5150);
DISPLAY INVISIBLE (-2923 5150);
FORCEPROP 2 LAST ROOM RISER1
J 0
(-3425 5200);
DISPLAY 0.829787 (-3425 5200);
PAINT RED (-3425 5200);
DISPLAY INVISIBLE (-3425 5200);
FORCEADD TAP..6
R 2
(-2925 5350);
FORCEPROP 3 LASTPIN (-2975 5350) SIG_NAME GMI_CPU1_G2_CPU0_G0_TX_DN<11>
J 0
(-2965 5360);
DISPLAY 0.659574 (-2965 5360);
PAINT MONO (-2965 5360);
DISPLAY INVISIBLE (-2965 5360);
FORCEPROP 1 LASTPIN (-2975 5350) BN 11
J 2
(-2923 5358);
DISPLAY 0.489362 (-2923 5358);
PAINT MONO (-2923 5358);
FORCEPROP 2 LAST BOM_COST IO_SLOT
J 0
(-3425 5450);
DISPLAY 0.829787 (-3425 5450);
DISPLAY INVISIBLE (-3425 5450);
FORCEPROP 2 LAST CDS_LIB standard
J 0
(-2925 5350);
DISPLAY INVISIBLE (-2925 5350);
FORCEPROP 1 LAST BODY_TYPE PLUMBING
J 2
(-2925 5300);
DISPLAY 0.702128 (-2925 5300);
PAINT GREEN (-2925 5300);
DISPLAY INVISIBLE (-2925 5300);
FORCEPROP 1 LAST HDL_TAP TRUE
J 2
(-3250 5225);
DISPLAY 0.702128 (-3250 5225);
PAINT GREEN (-3250 5225);
DISPLAY INVISIBLE (-3250 5225);
FORCEPROP 1 LAST PATH I420
J 2
(-2923 5350);
DISPLAY 0.872340 (-2923 5350);
PAINT GREEN (-2923 5350);
DISPLAY INVISIBLE (-2923 5350);
FORCEPROP 2 LAST ROOM RISER1
J 0
(-3425 5400);
DISPLAY 0.829787 (-3425 5400);
PAINT RED (-3425 5400);
DISPLAY INVISIBLE (-3425 5400);
FORCEADD TAP..6
R 2
(-2925 5450);
FORCEPROP 3 LASTPIN (-2975 5450) SIG_NAME GMI_CPU1_G2_CPU0_G0_TX_DN<12>
J 0
(-2965 5460);
DISPLAY 0.659574 (-2965 5460);
PAINT MONO (-2965 5460);
DISPLAY INVISIBLE (-2965 5460);
FORCEPROP 1 LASTPIN (-2975 5450) BN 12
J 2
(-2923 5458);
DISPLAY 0.489362 (-2923 5458);
PAINT MONO (-2923 5458);
FORCEPROP 2 LAST BOM_COST IO_SLOT
J 0
(-3425 5550);
DISPLAY 0.829787 (-3425 5550);
DISPLAY INVISIBLE (-3425 5550);
FORCEPROP 2 LAST CDS_LIB standard
J 0
(-2925 5450);
DISPLAY INVISIBLE (-2925 5450);
FORCEPROP 1 LAST BODY_TYPE PLUMBING
J 2
(-2925 5400);
DISPLAY 0.702128 (-2925 5400);
PAINT GREEN (-2925 5400);
DISPLAY INVISIBLE (-2925 5400);
FORCEPROP 1 LAST HDL_TAP TRUE
J 2
(-3250 5325);
DISPLAY 0.702128 (-3250 5325);
PAINT GREEN (-3250 5325);
DISPLAY INVISIBLE (-3250 5325);
FORCEPROP 1 LAST PATH I421
J 2
(-2923 5450);
DISPLAY 0.872340 (-2923 5450);
PAINT GREEN (-2923 5450);
DISPLAY INVISIBLE (-2923 5450);
FORCEPROP 2 LAST ROOM RISER1
J 0
(-3425 5500);
DISPLAY 0.829787 (-3425 5500);
PAINT RED (-3425 5500);
DISPLAY INVISIBLE (-3425 5500);
FORCEADD TAP..6
R 2
(-2925 5550);
FORCEPROP 3 LASTPIN (-2975 5550) SIG_NAME GMI_CPU1_G2_CPU0_G0_TX_DN<13>
J 0
(-2965 5560);
DISPLAY 0.659574 (-2965 5560);
PAINT MONO (-2965 5560);
DISPLAY INVISIBLE (-2965 5560);
FORCEPROP 1 LASTPIN (-2975 5550) BN 13
J 2
(-2923 5558);
DISPLAY 0.489362 (-2923 5558);
PAINT MONO (-2923 5558);
FORCEPROP 2 LAST BOM_COST IO_SLOT
J 0
(-3425 5650);
DISPLAY 0.829787 (-3425 5650);
DISPLAY INVISIBLE (-3425 5650);
FORCEPROP 2 LAST CDS_LIB standard
J 0
(-2925 5550);
DISPLAY INVISIBLE (-2925 5550);
FORCEPROP 1 LAST BODY_TYPE PLUMBING
J 2
(-2925 5500);
DISPLAY 0.702128 (-2925 5500);
PAINT GREEN (-2925 5500);
DISPLAY INVISIBLE (-2925 5500);
FORCEPROP 1 LAST HDL_TAP TRUE
J 2
(-3250 5425);
DISPLAY 0.702128 (-3250 5425);
PAINT GREEN (-3250 5425);
DISPLAY INVISIBLE (-3250 5425);
FORCEPROP 1 LAST PATH I422
J 2
(-2923 5550);
DISPLAY 0.872340 (-2923 5550);
PAINT GREEN (-2923 5550);
DISPLAY INVISIBLE (-2923 5550);
FORCEPROP 2 LAST ROOM RISER1
J 0
(-3425 5600);
DISPLAY 0.829787 (-3425 5600);
PAINT RED (-3425 5600);
DISPLAY INVISIBLE (-3425 5600);
FORCEADD TAP..6
R 2
(-2925 4850);
FORCEPROP 3 LASTPIN (-2975 4850) SIG_NAME GMI_CPU1_G2_CPU0_G0_TX_DN<6>
J 0
(-2965 4860);
DISPLAY 0.659574 (-2965 4860);
PAINT MONO (-2965 4860);
DISPLAY INVISIBLE (-2965 4860);
FORCEPROP 1 LASTPIN (-2975 4850) BN 6
J 2
(-2923 4858);
DISPLAY 0.489362 (-2923 4858);
PAINT MONO (-2923 4858);
FORCEPROP 2 LAST BOM_COST IO_SLOT
J 0
(-3425 4950);
DISPLAY 0.829787 (-3425 4950);
DISPLAY INVISIBLE (-3425 4950);
FORCEPROP 2 LAST CDS_LIB standard
J 0
(-2925 4850);
DISPLAY INVISIBLE (-2925 4850);
FORCEPROP 1 LAST BODY_TYPE PLUMBING
J 2
(-2925 4800);
DISPLAY 0.702128 (-2925 4800);
PAINT GREEN (-2925 4800);
DISPLAY INVISIBLE (-2925 4800);
FORCEPROP 1 LAST HDL_TAP TRUE
J 2
(-3250 4725);
DISPLAY 0.702128 (-3250 4725);
PAINT GREEN (-3250 4725);
DISPLAY INVISIBLE (-3250 4725);
FORCEPROP 1 LAST PATH I423
J 2
(-2923 4850);
DISPLAY 0.872340 (-2923 4850);
PAINT GREEN (-2923 4850);
DISPLAY INVISIBLE (-2923 4850);
FORCEPROP 2 LAST ROOM RISER1
J 0
(-3425 4900);
DISPLAY 0.829787 (-3425 4900);
PAINT RED (-3425 4900);
DISPLAY INVISIBLE (-3425 4900);
FORCEADD TAP..6
R 2
(-2925 4650);
FORCEPROP 3 LASTPIN (-2975 4650) SIG_NAME GMI_CPU1_G2_CPU0_G0_TX_DN<4>
J 0
(-2965 4660);
DISPLAY 0.659574 (-2965 4660);
PAINT MONO (-2965 4660);
DISPLAY INVISIBLE (-2965 4660);
FORCEPROP 1 LASTPIN (-2975 4650) BN 4
J 2
(-2923 4658);
DISPLAY 0.489362 (-2923 4658);
PAINT MONO (-2923 4658);
FORCEPROP 2 LAST BOM_COST IO_SLOT
J 0
(-3425 4750);
DISPLAY 0.829787 (-3425 4750);
DISPLAY INVISIBLE (-3425 4750);
FORCEPROP 2 LAST CDS_LIB standard
J 0
(-2925 4650);
DISPLAY INVISIBLE (-2925 4650);
FORCEPROP 1 LAST BODY_TYPE PLUMBING
J 2
(-2925 4600);
DISPLAY 0.702128 (-2925 4600);
PAINT GREEN (-2925 4600);
DISPLAY INVISIBLE (-2925 4600);
FORCEPROP 1 LAST HDL_TAP TRUE
J 2
(-3250 4525);
DISPLAY 0.702128 (-3250 4525);
PAINT GREEN (-3250 4525);
DISPLAY INVISIBLE (-3250 4525);
FORCEPROP 1 LAST PATH I424
J 2
(-2923 4650);
DISPLAY 0.872340 (-2923 4650);
PAINT GREEN (-2923 4650);
DISPLAY INVISIBLE (-2923 4650);
FORCEPROP 2 LAST ROOM RISER1
J 0
(-3425 4700);
DISPLAY 0.829787 (-3425 4700);
PAINT RED (-3425 4700);
DISPLAY INVISIBLE (-3425 4700);
FORCEADD TAP..6
R 2
(-2925 4750);
FORCEPROP 3 LASTPIN (-2975 4750) SIG_NAME GMI_CPU1_G2_CPU0_G0_TX_DN<5>
J 0
(-2965 4760);
DISPLAY 0.659574 (-2965 4760);
PAINT MONO (-2965 4760);
DISPLAY INVISIBLE (-2965 4760);
FORCEPROP 1 LASTPIN (-2975 4750) BN 5
J 2
(-2923 4758);
DISPLAY 0.489362 (-2923 4758);
PAINT MONO (-2923 4758);
FORCEPROP 2 LAST BOM_COST IO_SLOT
J 0
(-3425 4850);
DISPLAY 0.829787 (-3425 4850);
DISPLAY INVISIBLE (-3425 4850);
FORCEPROP 2 LAST CDS_LIB standard
J 0
(-2925 4750);
DISPLAY INVISIBLE (-2925 4750);
FORCEPROP 1 LAST BODY_TYPE PLUMBING
J 2
(-2925 4700);
DISPLAY 0.702128 (-2925 4700);
PAINT GREEN (-2925 4700);
DISPLAY INVISIBLE (-2925 4700);
FORCEPROP 1 LAST HDL_TAP TRUE
J 2
(-3250 4625);
DISPLAY 0.702128 (-3250 4625);
PAINT GREEN (-3250 4625);
DISPLAY INVISIBLE (-3250 4625);
FORCEPROP 1 LAST PATH I425
J 2
(-2923 4750);
DISPLAY 0.872340 (-2923 4750);
PAINT GREEN (-2923 4750);
DISPLAY INVISIBLE (-2923 4750);
FORCEPROP 2 LAST ROOM RISER1
J 0
(-3425 4800);
DISPLAY 0.829787 (-3425 4800);
PAINT RED (-3425 4800);
DISPLAY INVISIBLE (-3425 4800);
FORCEADD TAP..6
R 2
(-2925 5050);
FORCEPROP 3 LASTPIN (-2975 5050) SIG_NAME GMI_CPU1_G2_CPU0_G0_TX_DN<8>
J 0
(-2965 5060);
DISPLAY 0.659574 (-2965 5060);
PAINT MONO (-2965 5060);
DISPLAY INVISIBLE (-2965 5060);
FORCEPROP 1 LASTPIN (-2975 5050) BN 8
J 2
(-2923 5058);
DISPLAY 0.489362 (-2923 5058);
PAINT MONO (-2923 5058);
FORCEPROP 2 LAST BOM_COST IO_SLOT
J 0
(-3425 5150);
DISPLAY 0.829787 (-3425 5150);
DISPLAY INVISIBLE (-3425 5150);
FORCEPROP 2 LAST CDS_LIB standard
J 0
(-2925 5050);
DISPLAY INVISIBLE (-2925 5050);
FORCEPROP 1 LAST BODY_TYPE PLUMBING
J 2
(-2925 5000);
DISPLAY 0.702128 (-2925 5000);
PAINT GREEN (-2925 5000);
DISPLAY INVISIBLE (-2925 5000);
FORCEPROP 1 LAST HDL_TAP TRUE
J 2
(-3250 4925);
DISPLAY 0.702128 (-3250 4925);
PAINT GREEN (-3250 4925);
DISPLAY INVISIBLE (-3250 4925);
FORCEPROP 1 LAST PATH I426
J 2
(-2923 5050);
DISPLAY 0.872340 (-2923 5050);
PAINT GREEN (-2923 5050);
DISPLAY INVISIBLE (-2923 5050);
FORCEPROP 2 LAST ROOM RISER1
J 0
(-3425 5100);
DISPLAY 0.829787 (-3425 5100);
PAINT RED (-3425 5100);
DISPLAY INVISIBLE (-3425 5100);
FORCEADD TAP..6
R 2
(-2925 4950);
FORCEPROP 3 LASTPIN (-2975 4950) SIG_NAME GMI_CPU1_G2_CPU0_G0_TX_DN<7>
J 0
(-2965 4960);
DISPLAY 0.659574 (-2965 4960);
PAINT MONO (-2965 4960);
DISPLAY INVISIBLE (-2965 4960);
FORCEPROP 1 LASTPIN (-2975 4950) BN 7
J 2
(-2923 4958);
DISPLAY 0.489362 (-2923 4958);
PAINT MONO (-2923 4958);
FORCEPROP 2 LAST BOM_COST IO_SLOT
J 0
(-3425 5050);
DISPLAY 0.829787 (-3425 5050);
DISPLAY INVISIBLE (-3425 5050);
FORCEPROP 2 LAST CDS_LIB standard
J 0
(-2925 4950);
DISPLAY INVISIBLE (-2925 4950);
FORCEPROP 1 LAST BODY_TYPE PLUMBING
J 2
(-2925 4900);
DISPLAY 0.702128 (-2925 4900);
PAINT GREEN (-2925 4900);
DISPLAY INVISIBLE (-2925 4900);
FORCEPROP 1 LAST HDL_TAP TRUE
J 2
(-3250 4825);
DISPLAY 0.702128 (-3250 4825);
PAINT GREEN (-3250 4825);
DISPLAY INVISIBLE (-3250 4825);
FORCEPROP 1 LAST PATH I427
J 2
(-2923 4950);
DISPLAY 0.872340 (-2923 4950);
PAINT GREEN (-2923 4950);
DISPLAY INVISIBLE (-2923 4950);
FORCEPROP 2 LAST ROOM RISER1
J 0
(-3425 5000);
DISPLAY 0.829787 (-3425 5000);
PAINT RED (-3425 5000);
DISPLAY INVISIBLE (-3425 5000);
FORCEADD TAP..6
R 2
(-2925 4250);
FORCEPROP 3 LASTPIN (-2975 4250) SIG_NAME GMI_CPU1_G2_CPU0_G0_TX_DN<0>
J 0
(-2965 4260);
DISPLAY 0.659574 (-2965 4260);
PAINT MONO (-2965 4260);
DISPLAY INVISIBLE (-2965 4260);
FORCEPROP 1 LASTPIN (-2975 4250) BN 0
J 2
(-2923 4258);
DISPLAY 0.489362 (-2923 4258);
PAINT MONO (-2923 4258);
FORCEPROP 2 LAST BOM_COST IO_SLOT
J 0
(-3425 4350);
DISPLAY 0.829787 (-3425 4350);
DISPLAY INVISIBLE (-3425 4350);
FORCEPROP 2 LAST CDS_LIB standard
J 0
(-2925 4250);
DISPLAY INVISIBLE (-2925 4250);
FORCEPROP 1 LAST BODY_TYPE PLUMBING
J 2
(-2925 4200);
DISPLAY 0.702128 (-2925 4200);
PAINT GREEN (-2925 4200);
DISPLAY INVISIBLE (-2925 4200);
FORCEPROP 1 LAST HDL_TAP TRUE
J 2
(-3250 4125);
DISPLAY 0.702128 (-3250 4125);
PAINT GREEN (-3250 4125);
DISPLAY INVISIBLE (-3250 4125);
FORCEPROP 1 LAST PATH I428
J 2
(-2923 4250);
DISPLAY 0.872340 (-2923 4250);
PAINT GREEN (-2923 4250);
DISPLAY INVISIBLE (-2923 4250);
FORCEPROP 2 LAST ROOM RISER1
J 0
(-3425 4300);
DISPLAY 0.829787 (-3425 4300);
PAINT RED (-3425 4300);
DISPLAY INVISIBLE (-3425 4300);
FORCEADD TAP..6
R 2
(-2925 4550);
FORCEPROP 3 LASTPIN (-2975 4550) SIG_NAME GMI_CPU1_G2_CPU0_G0_TX_DN<3>
J 0
(-2965 4560);
DISPLAY 0.659574 (-2965 4560);
PAINT MONO (-2965 4560);
DISPLAY INVISIBLE (-2965 4560);
FORCEPROP 1 LASTPIN (-2975 4550) BN 3
J 2
(-2923 4558);
DISPLAY 0.489362 (-2923 4558);
PAINT MONO (-2923 4558);
FORCEPROP 2 LAST BOM_COST IO_SLOT
J 0
(-3425 4650);
DISPLAY 0.829787 (-3425 4650);
DISPLAY INVISIBLE (-3425 4650);
FORCEPROP 2 LAST CDS_LIB standard
J 0
(-2925 4550);
DISPLAY INVISIBLE (-2925 4550);
FORCEPROP 1 LAST BODY_TYPE PLUMBING
J 2
(-2925 4500);
DISPLAY 0.702128 (-2925 4500);
PAINT GREEN (-2925 4500);
DISPLAY INVISIBLE (-2925 4500);
FORCEPROP 1 LAST HDL_TAP TRUE
J 2
(-3250 4425);
DISPLAY 0.702128 (-3250 4425);
PAINT GREEN (-3250 4425);
DISPLAY INVISIBLE (-3250 4425);
FORCEPROP 1 LAST PATH I429
J 2
(-2923 4550);
DISPLAY 0.872340 (-2923 4550);
PAINT GREEN (-2923 4550);
DISPLAY INVISIBLE (-2923 4550);
FORCEPROP 2 LAST ROOM RISER1
J 0
(-3425 4600);
DISPLAY 0.829787 (-3425 4600);
PAINT RED (-3425 4600);
DISPLAY INVISIBLE (-3425 4600);
FORCEADD TAP..6
R 2
(-2925 4450);
FORCEPROP 3 LASTPIN (-2975 4450) SIG_NAME GMI_CPU1_G2_CPU0_G0_TX_DN<2>
J 0
(-2965 4460);
DISPLAY 0.659574 (-2965 4460);
PAINT MONO (-2965 4460);
DISPLAY INVISIBLE (-2965 4460);
FORCEPROP 1 LASTPIN (-2975 4450) BN 2
J 2
(-2923 4458);
DISPLAY 0.489362 (-2923 4458);
PAINT MONO (-2923 4458);
FORCEPROP 2 LAST BOM_COST IO_SLOT
J 0
(-3425 4550);
DISPLAY 0.829787 (-3425 4550);
DISPLAY INVISIBLE (-3425 4550);
FORCEPROP 2 LAST CDS_LIB standard
J 0
(-2925 4450);
DISPLAY INVISIBLE (-2925 4450);
FORCEPROP 1 LAST BODY_TYPE PLUMBING
J 2
(-2925 4400);
DISPLAY 0.702128 (-2925 4400);
PAINT GREEN (-2925 4400);
DISPLAY INVISIBLE (-2925 4400);
FORCEPROP 1 LAST HDL_TAP TRUE
J 2
(-3250 4325);
DISPLAY 0.702128 (-3250 4325);
PAINT GREEN (-3250 4325);
DISPLAY INVISIBLE (-3250 4325);
FORCEPROP 1 LAST PATH I430
J 2
(-2923 4450);
DISPLAY 0.872340 (-2923 4450);
PAINT GREEN (-2923 4450);
DISPLAY INVISIBLE (-2923 4450);
FORCEPROP 2 LAST ROOM RISER1
J 0
(-3425 4500);
DISPLAY 0.829787 (-3425 4500);
PAINT RED (-3425 4500);
DISPLAY INVISIBLE (-3425 4500);
FORCEADD TAP..6
R 2
(-2925 4350);
FORCEPROP 3 LASTPIN (-2975 4350) SIG_NAME GMI_CPU1_G2_CPU0_G0_TX_DN<1>
J 0
(-2965 4360);
DISPLAY 0.659574 (-2965 4360);
PAINT MONO (-2965 4360);
DISPLAY INVISIBLE (-2965 4360);
FORCEPROP 1 LASTPIN (-2975 4350) BN 1
J 2
(-2923 4358);
DISPLAY 0.489362 (-2923 4358);
PAINT MONO (-2923 4358);
FORCEPROP 2 LAST CDS_LIB standard
J 0
(-2925 4350);
DISPLAY INVISIBLE (-2925 4350);
FORCEPROP 2 LAST BOM_COST IO_SLOT
J 0
(-3425 4450);
DISPLAY 0.829787 (-3425 4450);
DISPLAY INVISIBLE (-3425 4450);
FORCEPROP 1 LAST BODY_TYPE PLUMBING
J 2
(-2925 4300);
DISPLAY 0.702128 (-2925 4300);
PAINT GREEN (-2925 4300);
DISPLAY INVISIBLE (-2925 4300);
FORCEPROP 1 LAST HDL_TAP TRUE
J 2
(-3250 4225);
DISPLAY 0.702128 (-3250 4225);
PAINT GREEN (-3250 4225);
DISPLAY INVISIBLE (-3250 4225);
FORCEPROP 1 LAST PATH I431
J 2
(-2923 4350);
DISPLAY 0.872340 (-2923 4350);
PAINT GREEN (-2923 4350);
DISPLAY INVISIBLE (-2923 4350);
FORCEPROP 2 LAST ROOM RISER1
J 0
(-3425 4400);
DISPLAY 0.829787 (-3425 4400);
PAINT RED (-3425 4400);
DISPLAY INVISIBLE (-3425 4400);
FORCEADD OFFPAGE..2
(-1775 3300);
FORCEPROP 2 LAST $XR0 22 
J 0
(-1586 3300);
DISPLAY 0.638298 (-1586 3300);
PAINT MONO (-1586 3300);
FORCEPROP 2 LAST CDS_LIB standard
J 0
(-1775 3300);
DISPLAY INVISIBLE (-1775 3300);
FORCEPROP 1 LAST OFFPAGE TRUE
J 0
(-1450 3175);
DISPLAY 0.872340 (-1450 3175);
PAINT GREEN (-1450 3175);
DISPLAY INVISIBLE (-1450 3175);
FORCEPROP 1 LAST COMMENT_BODY TRUE
J 0
(-1820 3205);
DISPLAY 0.872340 (-1820 3205);
PAINT GREEN (-1820 3205);
DISPLAY INVISIBLE (-1820 3205);
FORCEPROP 2 LAST PATH I432
J 0
(-1575 3350);
DISPLAY 1.021277 (-1575 3350);
DISPLAY INVISIBLE (-1575 3350);
FORCEADD TAP..6
R 2
(-2900 3075);
FORCEPROP 3 LASTPIN (-2950 3075) SIG_NAME GMI_CPU1_G3_CPU0_G1_TX_DN<15>
J 0
(-2940 3085);
DISPLAY 0.659574 (-2940 3085);
PAINT MONO (-2940 3085);
DISPLAY INVISIBLE (-2940 3085);
FORCEPROP 1 LASTPIN (-2950 3075) BN 15
J 2
(-2898 3083);
DISPLAY 0.489362 (-2898 3083);
PAINT MONO (-2898 3083);
FORCEPROP 2 LAST BOM_COST IO_SLOT
J 0
(-3400 3175);
DISPLAY 0.829787 (-3400 3175);
DISPLAY INVISIBLE (-3400 3175);
FORCEPROP 2 LAST CDS_LIB mstr_standard
J 0
(-2900 3075);
DISPLAY INVISIBLE (-2900 3075);
FORCEPROP 1 LAST BODY_TYPE PLUMBING
J 2
(-2900 3025);
DISPLAY 0.702128 (-2900 3025);
PAINT GREEN (-2900 3025);
DISPLAY INVISIBLE (-2900 3025);
FORCEPROP 1 LAST HDL_TAP TRUE
J 2
(-3225 2950);
DISPLAY 0.702128 (-3225 2950);
PAINT GREEN (-3225 2950);
DISPLAY INVISIBLE (-3225 2950);
FORCEPROP 1 LAST PATH I433
J 2
(-2898 3075);
DISPLAY 0.872340 (-2898 3075);
PAINT GREEN (-2898 3075);
DISPLAY INVISIBLE (-2898 3075);
FORCEPROP 2 LAST ROOM RISER1
J 0
(-3400 3125);
DISPLAY 0.829787 (-3400 3125);
PAINT RED (-3400 3125);
DISPLAY INVISIBLE (-3400 3125);
FORCEADD TAP..6
R 2
(-2900 2975);
FORCEPROP 3 LASTPIN (-2950 2975) SIG_NAME GMI_CPU1_G3_CPU0_G1_TX_DN<14>
J 0
(-2940 2985);
DISPLAY 0.659574 (-2940 2985);
PAINT MONO (-2940 2985);
DISPLAY INVISIBLE (-2940 2985);
FORCEPROP 1 LASTPIN (-2950 2975) BN 14
J 2
(-2898 2983);
DISPLAY 0.489362 (-2898 2983);
PAINT MONO (-2898 2983);
FORCEPROP 2 LAST CDS_LIB mstr_standard
J 0
(-2900 2975);
DISPLAY INVISIBLE (-2900 2975);
FORCEPROP 2 LAST BOM_COST IO_SLOT
J 0
(-3400 3075);
DISPLAY 0.829787 (-3400 3075);
DISPLAY INVISIBLE (-3400 3075);
FORCEPROP 1 LAST BODY_TYPE PLUMBING
J 2
(-2900 2925);
DISPLAY 0.702128 (-2900 2925);
PAINT GREEN (-2900 2925);
DISPLAY INVISIBLE (-2900 2925);
FORCEPROP 1 LAST HDL_TAP TRUE
J 2
(-3225 2850);
DISPLAY 0.702128 (-3225 2850);
PAINT GREEN (-3225 2850);
DISPLAY INVISIBLE (-3225 2850);
FORCEPROP 1 LAST PATH I434
J 2
(-2898 2975);
DISPLAY 0.872340 (-2898 2975);
PAINT GREEN (-2898 2975);
DISPLAY INVISIBLE (-2898 2975);
FORCEPROP 2 LAST ROOM RISER1
J 0
(-3400 3025);
DISPLAY 0.829787 (-3400 3025);
PAINT RED (-3400 3025);
DISPLAY INVISIBLE (-3400 3025);
FORCEADD TAP..6
R 2
(-2900 2875);
FORCEPROP 3 LASTPIN (-2950 2875) SIG_NAME GMI_CPU1_G3_CPU0_G1_TX_DN<13>
J 0
(-2940 2885);
DISPLAY 0.659574 (-2940 2885);
PAINT MONO (-2940 2885);
DISPLAY INVISIBLE (-2940 2885);
FORCEPROP 1 LASTPIN (-2950 2875) BN 13
J 2
(-2898 2883);
DISPLAY 0.489362 (-2898 2883);
PAINT MONO (-2898 2883);
FORCEPROP 2 LAST CDS_LIB standard
J 0
(-2900 2875);
DISPLAY INVISIBLE (-2900 2875);
FORCEPROP 2 LAST BOM_COST IO_SLOT
J 0
(-3400 2975);
DISPLAY 0.829787 (-3400 2975);
DISPLAY INVISIBLE (-3400 2975);
FORCEPROP 1 LAST BODY_TYPE PLUMBING
J 2
(-2900 2825);
DISPLAY 0.702128 (-2900 2825);
PAINT GREEN (-2900 2825);
DISPLAY INVISIBLE (-2900 2825);
FORCEPROP 1 LAST HDL_TAP TRUE
J 2
(-3225 2750);
DISPLAY 0.702128 (-3225 2750);
PAINT GREEN (-3225 2750);
DISPLAY INVISIBLE (-3225 2750);
FORCEPROP 1 LAST PATH I435
J 2
(-2898 2875);
DISPLAY 0.872340 (-2898 2875);
PAINT GREEN (-2898 2875);
DISPLAY INVISIBLE (-2898 2875);
FORCEPROP 2 LAST ROOM RISER1
J 0
(-3400 2925);
DISPLAY 0.829787 (-3400 2925);
PAINT RED (-3400 2925);
DISPLAY INVISIBLE (-3400 2925);
FORCEADD TAP..6
R 2
(-2900 2775);
FORCEPROP 3 LASTPIN (-2950 2775) SIG_NAME GMI_CPU1_G3_CPU0_G1_TX_DN<12>
J 0
(-2940 2785);
DISPLAY 0.659574 (-2940 2785);
PAINT MONO (-2940 2785);
DISPLAY INVISIBLE (-2940 2785);
FORCEPROP 1 LASTPIN (-2950 2775) BN 12
J 2
(-2898 2783);
DISPLAY 0.489362 (-2898 2783);
PAINT MONO (-2898 2783);
FORCEPROP 2 LAST CDS_LIB standard
J 0
(-2900 2775);
DISPLAY INVISIBLE (-2900 2775);
FORCEPROP 2 LAST BOM_COST IO_SLOT
J 0
(-3400 2875);
DISPLAY 0.829787 (-3400 2875);
DISPLAY INVISIBLE (-3400 2875);
FORCEPROP 1 LAST BODY_TYPE PLUMBING
J 2
(-2900 2725);
DISPLAY 0.702128 (-2900 2725);
PAINT GREEN (-2900 2725);
DISPLAY INVISIBLE (-2900 2725);
FORCEPROP 1 LAST HDL_TAP TRUE
J 2
(-3225 2650);
DISPLAY 0.702128 (-3225 2650);
PAINT GREEN (-3225 2650);
DISPLAY INVISIBLE (-3225 2650);
FORCEPROP 1 LAST PATH I436
J 2
(-2898 2775);
DISPLAY 0.872340 (-2898 2775);
PAINT GREEN (-2898 2775);
DISPLAY INVISIBLE (-2898 2775);
FORCEPROP 2 LAST ROOM RISER1
J 0
(-3400 2825);
DISPLAY 0.829787 (-3400 2825);
PAINT RED (-3400 2825);
DISPLAY INVISIBLE (-3400 2825);
FORCEADD TAP..6
R 2
(-2900 2675);
FORCEPROP 3 LASTPIN (-2950 2675) SIG_NAME GMI_CPU1_G3_CPU0_G1_TX_DN<11>
J 0
(-2940 2685);
DISPLAY 0.659574 (-2940 2685);
PAINT MONO (-2940 2685);
DISPLAY INVISIBLE (-2940 2685);
FORCEPROP 1 LASTPIN (-2950 2675) BN 11
J 2
(-2898 2683);
DISPLAY 0.489362 (-2898 2683);
PAINT MONO (-2898 2683);
FORCEPROP 2 LAST CDS_LIB standard
J 0
(-2900 2675);
DISPLAY INVISIBLE (-2900 2675);
FORCEPROP 2 LAST BOM_COST IO_SLOT
J 0
(-3400 2775);
DISPLAY 0.829787 (-3400 2775);
DISPLAY INVISIBLE (-3400 2775);
FORCEPROP 1 LAST BODY_TYPE PLUMBING
J 2
(-2900 2625);
DISPLAY 0.702128 (-2900 2625);
PAINT GREEN (-2900 2625);
DISPLAY INVISIBLE (-2900 2625);
FORCEPROP 1 LAST HDL_TAP TRUE
J 2
(-3225 2550);
DISPLAY 0.702128 (-3225 2550);
PAINT GREEN (-3225 2550);
DISPLAY INVISIBLE (-3225 2550);
FORCEPROP 1 LAST PATH I437
J 2
(-2898 2675);
DISPLAY 0.872340 (-2898 2675);
PAINT GREEN (-2898 2675);
DISPLAY INVISIBLE (-2898 2675);
FORCEPROP 2 LAST ROOM RISER1
J 0
(-3400 2725);
DISPLAY 0.829787 (-3400 2725);
PAINT RED (-3400 2725);
DISPLAY INVISIBLE (-3400 2725);
FORCEADD TAP..6
R 2
(-2900 2575);
FORCEPROP 3 LASTPIN (-2950 2575) SIG_NAME GMI_CPU1_G3_CPU0_G1_TX_DN<10>
J 0
(-2940 2585);
DISPLAY 0.659574 (-2940 2585);
PAINT MONO (-2940 2585);
DISPLAY INVISIBLE (-2940 2585);
FORCEPROP 1 LASTPIN (-2950 2575) BN 10
J 2
(-2898 2583);
DISPLAY 0.489362 (-2898 2583);
PAINT MONO (-2898 2583);
FORCEPROP 2 LAST CDS_LIB standard
J 0
(-2900 2575);
DISPLAY INVISIBLE (-2900 2575);
FORCEPROP 2 LAST BOM_COST IO_SLOT
J 0
(-3400 2675);
DISPLAY 0.829787 (-3400 2675);
DISPLAY INVISIBLE (-3400 2675);
FORCEPROP 1 LAST BODY_TYPE PLUMBING
J 2
(-2900 2525);
DISPLAY 0.702128 (-2900 2525);
PAINT GREEN (-2900 2525);
DISPLAY INVISIBLE (-2900 2525);
FORCEPROP 1 LAST HDL_TAP TRUE
J 2
(-3225 2450);
DISPLAY 0.702128 (-3225 2450);
PAINT GREEN (-3225 2450);
DISPLAY INVISIBLE (-3225 2450);
FORCEPROP 1 LAST PATH I438
J 2
(-2898 2575);
DISPLAY 0.872340 (-2898 2575);
PAINT GREEN (-2898 2575);
DISPLAY INVISIBLE (-2898 2575);
FORCEPROP 2 LAST ROOM RISER1
J 0
(-3400 2625);
DISPLAY 0.829787 (-3400 2625);
PAINT RED (-3400 2625);
DISPLAY INVISIBLE (-3400 2625);
FORCEADD TAP..6
R 2
(-2900 2475);
FORCEPROP 3 LASTPIN (-2950 2475) SIG_NAME GMI_CPU1_G3_CPU0_G1_TX_DN<9>
J 0
(-2940 2485);
DISPLAY 0.659574 (-2940 2485);
PAINT MONO (-2940 2485);
DISPLAY INVISIBLE (-2940 2485);
FORCEPROP 1 LASTPIN (-2950 2475) BN 9
J 2
(-2898 2483);
DISPLAY 0.489362 (-2898 2483);
PAINT MONO (-2898 2483);
FORCEPROP 2 LAST CDS_LIB standard
J 0
(-2900 2475);
DISPLAY INVISIBLE (-2900 2475);
FORCEPROP 2 LAST BOM_COST IO_SLOT
J 0
(-3400 2575);
DISPLAY 0.829787 (-3400 2575);
DISPLAY INVISIBLE (-3400 2575);
FORCEPROP 1 LAST BODY_TYPE PLUMBING
J 2
(-2900 2425);
DISPLAY 0.702128 (-2900 2425);
PAINT GREEN (-2900 2425);
DISPLAY INVISIBLE (-2900 2425);
FORCEPROP 1 LAST HDL_TAP TRUE
J 2
(-3225 2350);
DISPLAY 0.702128 (-3225 2350);
PAINT GREEN (-3225 2350);
DISPLAY INVISIBLE (-3225 2350);
FORCEPROP 1 LAST PATH I439
J 2
(-2898 2475);
DISPLAY 0.872340 (-2898 2475);
PAINT GREEN (-2898 2475);
DISPLAY INVISIBLE (-2898 2475);
FORCEPROP 2 LAST ROOM RISER1
J 0
(-3400 2525);
DISPLAY 0.829787 (-3400 2525);
PAINT RED (-3400 2525);
DISPLAY INVISIBLE (-3400 2525);
FORCEADD TAP..6
R 2
(-2900 2375);
FORCEPROP 3 LASTPIN (-2950 2375) SIG_NAME GMI_CPU1_G3_CPU0_G1_TX_DN<8>
J 0
(-2940 2385);
DISPLAY 0.659574 (-2940 2385);
PAINT MONO (-2940 2385);
DISPLAY INVISIBLE (-2940 2385);
FORCEPROP 1 LASTPIN (-2950 2375) BN 8
J 2
(-2898 2383);
DISPLAY 0.489362 (-2898 2383);
PAINT MONO (-2898 2383);
FORCEPROP 2 LAST CDS_LIB standard
J 0
(-2900 2375);
DISPLAY INVISIBLE (-2900 2375);
FORCEPROP 2 LAST BOM_COST IO_SLOT
J 0
(-3400 2475);
DISPLAY 0.829787 (-3400 2475);
DISPLAY INVISIBLE (-3400 2475);
FORCEPROP 1 LAST BODY_TYPE PLUMBING
J 2
(-2900 2325);
DISPLAY 0.702128 (-2900 2325);
PAINT GREEN (-2900 2325);
DISPLAY INVISIBLE (-2900 2325);
FORCEPROP 1 LAST HDL_TAP TRUE
J 2
(-3225 2250);
DISPLAY 0.702128 (-3225 2250);
PAINT GREEN (-3225 2250);
DISPLAY INVISIBLE (-3225 2250);
FORCEPROP 1 LAST PATH I440
J 2
(-2898 2375);
DISPLAY 0.872340 (-2898 2375);
PAINT GREEN (-2898 2375);
DISPLAY INVISIBLE (-2898 2375);
FORCEPROP 2 LAST ROOM RISER1
J 0
(-3400 2425);
DISPLAY 0.829787 (-3400 2425);
PAINT RED (-3400 2425);
DISPLAY INVISIBLE (-3400 2425);
FORCEADD TAP..6
R 2
(-2900 2275);
FORCEPROP 3 LASTPIN (-2950 2275) SIG_NAME GMI_CPU1_G3_CPU0_G1_TX_DN<7>
J 0
(-2940 2285);
DISPLAY 0.659574 (-2940 2285);
PAINT MONO (-2940 2285);
DISPLAY INVISIBLE (-2940 2285);
FORCEPROP 1 LASTPIN (-2950 2275) BN 7
J 2
(-2898 2283);
DISPLAY 0.489362 (-2898 2283);
PAINT MONO (-2898 2283);
FORCEPROP 2 LAST CDS_LIB standard
J 0
(-2900 2275);
DISPLAY INVISIBLE (-2900 2275);
FORCEPROP 2 LAST BOM_COST IO_SLOT
J 0
(-3400 2375);
DISPLAY 0.829787 (-3400 2375);
DISPLAY INVISIBLE (-3400 2375);
FORCEPROP 1 LAST BODY_TYPE PLUMBING
J 2
(-2900 2225);
DISPLAY 0.702128 (-2900 2225);
PAINT GREEN (-2900 2225);
DISPLAY INVISIBLE (-2900 2225);
FORCEPROP 1 LAST HDL_TAP TRUE
J 2
(-3225 2150);
DISPLAY 0.702128 (-3225 2150);
PAINT GREEN (-3225 2150);
DISPLAY INVISIBLE (-3225 2150);
FORCEPROP 1 LAST PATH I441
J 2
(-2898 2275);
DISPLAY 0.872340 (-2898 2275);
PAINT GREEN (-2898 2275);
DISPLAY INVISIBLE (-2898 2275);
FORCEPROP 2 LAST ROOM RISER1
J 0
(-3400 2325);
DISPLAY 0.829787 (-3400 2325);
PAINT RED (-3400 2325);
DISPLAY INVISIBLE (-3400 2325);
FORCEADD TAP..6
R 2
(-2900 2175);
FORCEPROP 3 LASTPIN (-2950 2175) SIG_NAME GMI_CPU1_G3_CPU0_G1_TX_DN<6>
J 0
(-2940 2185);
DISPLAY 0.659574 (-2940 2185);
PAINT MONO (-2940 2185);
DISPLAY INVISIBLE (-2940 2185);
FORCEPROP 1 LASTPIN (-2950 2175) BN 6
J 2
(-2898 2183);
DISPLAY 0.489362 (-2898 2183);
PAINT MONO (-2898 2183);
FORCEPROP 2 LAST CDS_LIB standard
J 0
(-2900 2175);
DISPLAY INVISIBLE (-2900 2175);
FORCEPROP 2 LAST BOM_COST IO_SLOT
J 0
(-3400 2275);
DISPLAY 0.829787 (-3400 2275);
DISPLAY INVISIBLE (-3400 2275);
FORCEPROP 1 LAST BODY_TYPE PLUMBING
J 2
(-2900 2125);
DISPLAY 0.702128 (-2900 2125);
PAINT GREEN (-2900 2125);
DISPLAY INVISIBLE (-2900 2125);
FORCEPROP 1 LAST HDL_TAP TRUE
J 2
(-3225 2050);
DISPLAY 0.702128 (-3225 2050);
PAINT GREEN (-3225 2050);
DISPLAY INVISIBLE (-3225 2050);
FORCEPROP 1 LAST PATH I442
J 2
(-2898 2175);
DISPLAY 0.872340 (-2898 2175);
PAINT GREEN (-2898 2175);
DISPLAY INVISIBLE (-2898 2175);
FORCEPROP 2 LAST ROOM RISER1
J 0
(-3400 2225);
DISPLAY 0.829787 (-3400 2225);
PAINT RED (-3400 2225);
DISPLAY INVISIBLE (-3400 2225);
FORCEADD TAP..6
R 2
(-2900 2075);
FORCEPROP 3 LASTPIN (-2950 2075) SIG_NAME GMI_CPU1_G3_CPU0_G1_TX_DN<5>
J 0
(-2940 2085);
DISPLAY 0.659574 (-2940 2085);
PAINT MONO (-2940 2085);
DISPLAY INVISIBLE (-2940 2085);
FORCEPROP 1 LASTPIN (-2950 2075) BN 5
J 2
(-2898 2083);
DISPLAY 0.489362 (-2898 2083);
PAINT MONO (-2898 2083);
FORCEPROP 2 LAST CDS_LIB standard
J 0
(-2900 2075);
DISPLAY INVISIBLE (-2900 2075);
FORCEPROP 2 LAST BOM_COST IO_SLOT
J 0
(-3400 2175);
DISPLAY 0.829787 (-3400 2175);
DISPLAY INVISIBLE (-3400 2175);
FORCEPROP 1 LAST BODY_TYPE PLUMBING
J 2
(-2900 2025);
DISPLAY 0.702128 (-2900 2025);
PAINT GREEN (-2900 2025);
DISPLAY INVISIBLE (-2900 2025);
FORCEPROP 1 LAST HDL_TAP TRUE
J 2
(-3225 1950);
DISPLAY 0.702128 (-3225 1950);
PAINT GREEN (-3225 1950);
DISPLAY INVISIBLE (-3225 1950);
FORCEPROP 1 LAST PATH I443
J 2
(-2898 2075);
DISPLAY 0.872340 (-2898 2075);
PAINT GREEN (-2898 2075);
DISPLAY INVISIBLE (-2898 2075);
FORCEPROP 2 LAST ROOM RISER1
J 0
(-3400 2125);
DISPLAY 0.829787 (-3400 2125);
PAINT RED (-3400 2125);
DISPLAY INVISIBLE (-3400 2125);
FORCEADD TAP..6
R 2
(-2900 1975);
FORCEPROP 3 LASTPIN (-2950 1975) SIG_NAME GMI_CPU1_G3_CPU0_G1_TX_DN<4>
J 0
(-2940 1985);
DISPLAY 0.659574 (-2940 1985);
PAINT MONO (-2940 1985);
DISPLAY INVISIBLE (-2940 1985);
FORCEPROP 1 LASTPIN (-2950 1975) BN 4
J 2
(-2898 1983);
DISPLAY 0.489362 (-2898 1983);
PAINT MONO (-2898 1983);
FORCEPROP 2 LAST CDS_LIB standard
J 0
(-2900 1975);
DISPLAY INVISIBLE (-2900 1975);
FORCEPROP 2 LAST BOM_COST IO_SLOT
J 0
(-3400 2075);
DISPLAY 0.829787 (-3400 2075);
DISPLAY INVISIBLE (-3400 2075);
FORCEPROP 1 LAST BODY_TYPE PLUMBING
J 2
(-2900 1925);
DISPLAY 0.702128 (-2900 1925);
PAINT GREEN (-2900 1925);
DISPLAY INVISIBLE (-2900 1925);
FORCEPROP 1 LAST HDL_TAP TRUE
J 2
(-3225 1850);
DISPLAY 0.702128 (-3225 1850);
PAINT GREEN (-3225 1850);
DISPLAY INVISIBLE (-3225 1850);
FORCEPROP 1 LAST PATH I444
J 2
(-2898 1975);
DISPLAY 0.872340 (-2898 1975);
PAINT GREEN (-2898 1975);
DISPLAY INVISIBLE (-2898 1975);
FORCEPROP 2 LAST ROOM RISER1
J 0
(-3400 2025);
DISPLAY 0.829787 (-3400 2025);
PAINT RED (-3400 2025);
DISPLAY INVISIBLE (-3400 2025);
FORCEADD TAP..6
R 2
(-2900 1875);
FORCEPROP 3 LASTPIN (-2950 1875) SIG_NAME GMI_CPU1_G3_CPU0_G1_TX_DN<3>
J 0
(-2940 1885);
DISPLAY 0.659574 (-2940 1885);
PAINT MONO (-2940 1885);
DISPLAY INVISIBLE (-2940 1885);
FORCEPROP 1 LASTPIN (-2950 1875) BN 3
J 2
(-2898 1883);
DISPLAY 0.489362 (-2898 1883);
PAINT MONO (-2898 1883);
FORCEPROP 2 LAST CDS_LIB standard
J 0
(-2900 1875);
DISPLAY INVISIBLE (-2900 1875);
FORCEPROP 2 LAST BOM_COST IO_SLOT
J 0
(-3400 1975);
DISPLAY 0.829787 (-3400 1975);
DISPLAY INVISIBLE (-3400 1975);
FORCEPROP 1 LAST BODY_TYPE PLUMBING
J 2
(-2900 1825);
DISPLAY 0.702128 (-2900 1825);
PAINT GREEN (-2900 1825);
DISPLAY INVISIBLE (-2900 1825);
FORCEPROP 1 LAST HDL_TAP TRUE
J 2
(-3225 1750);
DISPLAY 0.702128 (-3225 1750);
PAINT GREEN (-3225 1750);
DISPLAY INVISIBLE (-3225 1750);
FORCEPROP 1 LAST PATH I445
J 2
(-2898 1875);
DISPLAY 0.872340 (-2898 1875);
PAINT GREEN (-2898 1875);
DISPLAY INVISIBLE (-2898 1875);
FORCEPROP 2 LAST ROOM RISER1
J 0
(-3400 1925);
DISPLAY 0.829787 (-3400 1925);
PAINT RED (-3400 1925);
DISPLAY INVISIBLE (-3400 1925);
FORCEADD TAP..6
R 2
(-2900 1675);
FORCEPROP 3 LASTPIN (-2950 1675) SIG_NAME GMI_CPU1_G3_CPU0_G1_TX_DN<1>
J 0
(-2940 1685);
DISPLAY 0.659574 (-2940 1685);
PAINT MONO (-2940 1685);
DISPLAY INVISIBLE (-2940 1685);
FORCEPROP 1 LASTPIN (-2950 1675) BN 1
J 2
(-2898 1683);
DISPLAY 0.489362 (-2898 1683);
PAINT MONO (-2898 1683);
FORCEPROP 2 LAST BOM_COST IO_SLOT
J 0
(-3400 1775);
DISPLAY 0.829787 (-3400 1775);
DISPLAY INVISIBLE (-3400 1775);
FORCEPROP 2 LAST CDS_LIB standard
J 0
(-2900 1675);
DISPLAY INVISIBLE (-2900 1675);
FORCEPROP 1 LAST BODY_TYPE PLUMBING
J 2
(-2900 1625);
DISPLAY 0.702128 (-2900 1625);
PAINT GREEN (-2900 1625);
DISPLAY INVISIBLE (-2900 1625);
FORCEPROP 1 LAST HDL_TAP TRUE
J 2
(-3225 1550);
DISPLAY 0.702128 (-3225 1550);
PAINT GREEN (-3225 1550);
DISPLAY INVISIBLE (-3225 1550);
FORCEPROP 1 LAST PATH I446
J 2
(-2898 1675);
DISPLAY 0.872340 (-2898 1675);
PAINT GREEN (-2898 1675);
DISPLAY INVISIBLE (-2898 1675);
FORCEPROP 2 LAST ROOM RISER1
J 0
(-3400 1725);
DISPLAY 0.829787 (-3400 1725);
PAINT RED (-3400 1725);
DISPLAY INVISIBLE (-3400 1725);
FORCEADD TAP..6
R 2
(-2900 1775);
FORCEPROP 3 LASTPIN (-2950 1775) SIG_NAME GMI_CPU1_G3_CPU0_G1_TX_DN<2>
J 0
(-2940 1785);
DISPLAY 0.659574 (-2940 1785);
PAINT MONO (-2940 1785);
DISPLAY INVISIBLE (-2940 1785);
FORCEPROP 1 LASTPIN (-2950 1775) BN 2
J 2
(-2898 1783);
DISPLAY 0.489362 (-2898 1783);
PAINT MONO (-2898 1783);
FORCEPROP 2 LAST CDS_LIB standard
J 0
(-2900 1775);
DISPLAY INVISIBLE (-2900 1775);
FORCEPROP 2 LAST BOM_COST IO_SLOT
J 0
(-3400 1875);
DISPLAY 0.829787 (-3400 1875);
DISPLAY INVISIBLE (-3400 1875);
FORCEPROP 1 LAST BODY_TYPE PLUMBING
J 2
(-2900 1725);
DISPLAY 0.702128 (-2900 1725);
PAINT GREEN (-2900 1725);
DISPLAY INVISIBLE (-2900 1725);
FORCEPROP 1 LAST HDL_TAP TRUE
J 2
(-3225 1650);
DISPLAY 0.702128 (-3225 1650);
PAINT GREEN (-3225 1650);
DISPLAY INVISIBLE (-3225 1650);
FORCEPROP 1 LAST PATH I447
J 2
(-2898 1775);
DISPLAY 0.872340 (-2898 1775);
PAINT GREEN (-2898 1775);
DISPLAY INVISIBLE (-2898 1775);
FORCEPROP 2 LAST ROOM RISER1
J 0
(-3400 1825);
DISPLAY 0.829787 (-3400 1825);
PAINT RED (-3400 1825);
DISPLAY INVISIBLE (-3400 1825);
FORCEADD TAP..6
R 2
(-2900 1575);
FORCEPROP 3 LASTPIN (-2950 1575) SIG_NAME GMI_CPU1_G3_CPU0_G1_TX_DN<0>
J 0
(-2940 1585);
DISPLAY 0.659574 (-2940 1585);
PAINT MONO (-2940 1585);
DISPLAY INVISIBLE (-2940 1585);
FORCEPROP 1 LASTPIN (-2950 1575) BN 0
J 2
(-2898 1583);
DISPLAY 0.489362 (-2898 1583);
PAINT MONO (-2898 1583);
FORCEPROP 2 LAST CDS_LIB standard
J 0
(-2900 1575);
DISPLAY INVISIBLE (-2900 1575);
FORCEPROP 2 LAST BOM_COST IO_SLOT
J 0
(-3400 1675);
DISPLAY 0.829787 (-3400 1675);
DISPLAY INVISIBLE (-3400 1675);
FORCEPROP 1 LAST BODY_TYPE PLUMBING
J 2
(-2900 1525);
DISPLAY 0.702128 (-2900 1525);
PAINT GREEN (-2900 1525);
DISPLAY INVISIBLE (-2900 1525);
FORCEPROP 1 LAST HDL_TAP TRUE
J 2
(-3225 1450);
DISPLAY 0.702128 (-3225 1450);
PAINT GREEN (-3225 1450);
DISPLAY INVISIBLE (-3225 1450);
FORCEPROP 1 LAST PATH I448
J 2
(-2898 1575);
DISPLAY 0.872340 (-2898 1575);
PAINT GREEN (-2898 1575);
DISPLAY INVISIBLE (-2898 1575);
FORCEPROP 2 LAST ROOM RISER1
J 0
(-3400 1625);
DISPLAY 0.829787 (-3400 1625);
PAINT RED (-3400 1625);
DISPLAY INVISIBLE (-3400 1625);
FORCEADD TAP..6
(-6625 3075);
FORCEPROP 3 LASTPIN (-6575 3075) SIG_NAME GMI_CPU0_G1_CPU1_G3_TX_DN<15>
J 0
(-6565 3085);
DISPLAY 0.659574 (-6565 3085);
PAINT MONO (-6565 3085);
DISPLAY INVISIBLE (-6565 3085);
FORCEPROP 1 LASTPIN (-6575 3075) BN 15
J 0
(-6627 3083);
DISPLAY 0.489362 (-6627 3083);
PAINT MONO (-6627 3083);
FORCEPROP 2 LAST CDS_LIB mstr_standard
J 0
(-6625 3075);
DISPLAY INVISIBLE (-6625 3075);
FORCEPROP 1 LAST BODY_TYPE PLUMBING
J 0
(-6625 3025);
DISPLAY 0.574468 (-6625 3025);
PAINT GREEN (-6625 3025);
DISPLAY INVISIBLE (-6625 3025);
FORCEPROP 1 LAST HDL_TAP TRUE
J 0
(-6300 2950);
DISPLAY 0.574468 (-6300 2950);
PAINT GREEN (-6300 2950);
DISPLAY INVISIBLE (-6300 2950);
FORCEPROP 1 LAST PATH I449
J 0
(-6627 3075);
DISPLAY 0.872340 (-6627 3075);
PAINT GREEN (-6627 3075);
DISPLAY INVISIBLE (-6627 3075);
FORCEADD TAP..6
(-6625 2975);
FORCEPROP 3 LASTPIN (-6575 2975) SIG_NAME GMI_CPU0_G1_CPU1_G3_TX_DN<14>
J 0
(-6565 2985);
DISPLAY 0.659574 (-6565 2985);
PAINT MONO (-6565 2985);
DISPLAY INVISIBLE (-6565 2985);
FORCEPROP 1 LASTPIN (-6575 2975) BN 14
J 0
(-6627 2983);
DISPLAY 0.489362 (-6627 2983);
PAINT MONO (-6627 2983);
FORCEPROP 2 LAST CDS_LIB mstr_standard
J 0
(-6625 2975);
DISPLAY INVISIBLE (-6625 2975);
FORCEPROP 1 LAST BODY_TYPE PLUMBING
J 0
(-6625 2925);
DISPLAY 0.574468 (-6625 2925);
PAINT GREEN (-6625 2925);
DISPLAY INVISIBLE (-6625 2925);
FORCEPROP 1 LAST HDL_TAP TRUE
J 0
(-6300 2850);
DISPLAY 0.574468 (-6300 2850);
PAINT GREEN (-6300 2850);
DISPLAY INVISIBLE (-6300 2850);
FORCEPROP 1 LAST PATH I450
J 0
(-6627 2975);
DISPLAY 0.872340 (-6627 2975);
PAINT GREEN (-6627 2975);
DISPLAY INVISIBLE (-6627 2975);
FORCEADD TAP..6
(-6625 2875);
FORCEPROP 3 LASTPIN (-6575 2875) SIG_NAME GMI_CPU0_G1_CPU1_G3_TX_DN<13>
J 0
(-6565 2885);
DISPLAY 0.659574 (-6565 2885);
PAINT MONO (-6565 2885);
DISPLAY INVISIBLE (-6565 2885);
FORCEPROP 1 LASTPIN (-6575 2875) BN 13
J 0
(-6627 2883);
DISPLAY 0.489362 (-6627 2883);
PAINT MONO (-6627 2883);
FORCEPROP 2 LAST CDS_LIB standard
J 0
(-6625 2875);
DISPLAY INVISIBLE (-6625 2875);
FORCEPROP 1 LAST BODY_TYPE PLUMBING
J 0
(-6625 2825);
DISPLAY 0.574468 (-6625 2825);
PAINT GREEN (-6625 2825);
DISPLAY INVISIBLE (-6625 2825);
FORCEPROP 1 LAST HDL_TAP TRUE
J 0
(-6300 2750);
DISPLAY 0.574468 (-6300 2750);
PAINT GREEN (-6300 2750);
DISPLAY INVISIBLE (-6300 2750);
FORCEPROP 1 LAST PATH I451
J 0
(-6627 2875);
DISPLAY 0.872340 (-6627 2875);
PAINT GREEN (-6627 2875);
DISPLAY INVISIBLE (-6627 2875);
FORCEADD TAP..6
(-6625 2775);
FORCEPROP 3 LASTPIN (-6575 2775) SIG_NAME GMI_CPU0_G1_CPU1_G3_TX_DN<12>
J 0
(-6565 2785);
DISPLAY 0.659574 (-6565 2785);
PAINT MONO (-6565 2785);
DISPLAY INVISIBLE (-6565 2785);
FORCEPROP 1 LASTPIN (-6575 2775) BN 12
J 0
(-6627 2783);
DISPLAY 0.489362 (-6627 2783);
PAINT MONO (-6627 2783);
FORCEPROP 2 LAST CDS_LIB standard
J 0
(-6625 2775);
DISPLAY INVISIBLE (-6625 2775);
FORCEPROP 1 LAST BODY_TYPE PLUMBING
J 0
(-6625 2725);
DISPLAY 0.574468 (-6625 2725);
PAINT GREEN (-6625 2725);
DISPLAY INVISIBLE (-6625 2725);
FORCEPROP 1 LAST HDL_TAP TRUE
J 0
(-6300 2650);
DISPLAY 0.574468 (-6300 2650);
PAINT GREEN (-6300 2650);
DISPLAY INVISIBLE (-6300 2650);
FORCEPROP 1 LAST PATH I452
J 0
(-6627 2775);
DISPLAY 0.872340 (-6627 2775);
PAINT GREEN (-6627 2775);
DISPLAY INVISIBLE (-6627 2775);
FORCEADD TAP..6
(-6625 2675);
FORCEPROP 3 LASTPIN (-6575 2675) SIG_NAME GMI_CPU0_G1_CPU1_G3_TX_DN<11>
J 0
(-6565 2685);
DISPLAY 0.659574 (-6565 2685);
PAINT MONO (-6565 2685);
DISPLAY INVISIBLE (-6565 2685);
FORCEPROP 1 LASTPIN (-6575 2675) BN 11
J 0
(-6627 2683);
DISPLAY 0.489362 (-6627 2683);
PAINT MONO (-6627 2683);
FORCEPROP 2 LAST CDS_LIB standard
J 0
(-6625 2675);
DISPLAY INVISIBLE (-6625 2675);
FORCEPROP 1 LAST BODY_TYPE PLUMBING
J 0
(-6625 2625);
DISPLAY 0.574468 (-6625 2625);
PAINT GREEN (-6625 2625);
DISPLAY INVISIBLE (-6625 2625);
FORCEPROP 1 LAST HDL_TAP TRUE
J 0
(-6300 2550);
DISPLAY 0.574468 (-6300 2550);
PAINT GREEN (-6300 2550);
DISPLAY INVISIBLE (-6300 2550);
FORCEPROP 1 LAST PATH I453
J 0
(-6627 2675);
DISPLAY 0.872340 (-6627 2675);
PAINT GREEN (-6627 2675);
DISPLAY INVISIBLE (-6627 2675);
FORCEADD TAP..6
(-6625 2475);
FORCEPROP 3 LASTPIN (-6575 2475) SIG_NAME GMI_CPU0_G1_CPU1_G3_TX_DN<9>
J 0
(-6565 2485);
DISPLAY 0.659574 (-6565 2485);
PAINT MONO (-6565 2485);
DISPLAY INVISIBLE (-6565 2485);
FORCEPROP 1 LASTPIN (-6575 2475) BN 9
J 0
(-6627 2483);
DISPLAY 0.489362 (-6627 2483);
PAINT MONO (-6627 2483);
FORCEPROP 2 LAST CDS_LIB standard
J 0
(-6625 2475);
DISPLAY INVISIBLE (-6625 2475);
FORCEPROP 1 LAST BODY_TYPE PLUMBING
J 0
(-6625 2425);
DISPLAY 0.574468 (-6625 2425);
PAINT GREEN (-6625 2425);
DISPLAY INVISIBLE (-6625 2425);
FORCEPROP 1 LAST HDL_TAP TRUE
J 0
(-6300 2350);
DISPLAY 0.574468 (-6300 2350);
PAINT GREEN (-6300 2350);
DISPLAY INVISIBLE (-6300 2350);
FORCEPROP 1 LAST PATH I454
J 0
(-6627 2475);
DISPLAY 0.872340 (-6627 2475);
PAINT GREEN (-6627 2475);
DISPLAY INVISIBLE (-6627 2475);
FORCEADD TAP..6
(-6625 2575);
FORCEPROP 3 LASTPIN (-6575 2575) SIG_NAME GMI_CPU0_G1_CPU1_G3_TX_DN<10>
J 0
(-6565 2585);
DISPLAY 0.659574 (-6565 2585);
PAINT MONO (-6565 2585);
DISPLAY INVISIBLE (-6565 2585);
FORCEPROP 1 LASTPIN (-6575 2575) BN 10
J 0
(-6627 2583);
DISPLAY 0.489362 (-6627 2583);
PAINT MONO (-6627 2583);
FORCEPROP 2 LAST CDS_LIB standard
J 0
(-6625 2575);
DISPLAY INVISIBLE (-6625 2575);
FORCEPROP 1 LAST BODY_TYPE PLUMBING
J 0
(-6625 2525);
DISPLAY 0.574468 (-6625 2525);
PAINT GREEN (-6625 2525);
DISPLAY INVISIBLE (-6625 2525);
FORCEPROP 1 LAST HDL_TAP TRUE
J 0
(-6300 2450);
DISPLAY 0.574468 (-6300 2450);
PAINT GREEN (-6300 2450);
DISPLAY INVISIBLE (-6300 2450);
FORCEPROP 1 LAST PATH I455
J 0
(-6627 2575);
DISPLAY 0.872340 (-6627 2575);
PAINT GREEN (-6627 2575);
DISPLAY INVISIBLE (-6627 2575);
FORCEADD TAP..6
(-6625 2375);
FORCEPROP 3 LASTPIN (-6575 2375) SIG_NAME GMI_CPU0_G1_CPU1_G3_TX_DN<8>
J 0
(-6565 2385);
DISPLAY 0.659574 (-6565 2385);
PAINT MONO (-6565 2385);
DISPLAY INVISIBLE (-6565 2385);
FORCEPROP 1 LASTPIN (-6575 2375) BN 8
J 0
(-6627 2383);
DISPLAY 0.489362 (-6627 2383);
PAINT MONO (-6627 2383);
FORCEPROP 2 LAST CDS_LIB standard
J 0
(-6625 2375);
DISPLAY INVISIBLE (-6625 2375);
FORCEPROP 1 LAST BODY_TYPE PLUMBING
J 0
(-6625 2325);
DISPLAY 0.574468 (-6625 2325);
PAINT GREEN (-6625 2325);
DISPLAY INVISIBLE (-6625 2325);
FORCEPROP 1 LAST HDL_TAP TRUE
J 0
(-6300 2250);
DISPLAY 0.574468 (-6300 2250);
PAINT GREEN (-6300 2250);
DISPLAY INVISIBLE (-6300 2250);
FORCEPROP 1 LAST PATH I456
J 0
(-6627 2375);
DISPLAY 0.872340 (-6627 2375);
PAINT GREEN (-6627 2375);
DISPLAY INVISIBLE (-6627 2375);
FORCEADD TAP..6
(-6625 2275);
FORCEPROP 3 LASTPIN (-6575 2275) SIG_NAME GMI_CPU0_G1_CPU1_G3_TX_DN<7>
J 0
(-6565 2285);
DISPLAY 0.659574 (-6565 2285);
PAINT MONO (-6565 2285);
DISPLAY INVISIBLE (-6565 2285);
FORCEPROP 1 LASTPIN (-6575 2275) BN 7
J 0
(-6627 2283);
DISPLAY 0.489362 (-6627 2283);
PAINT MONO (-6627 2283);
FORCEPROP 2 LAST CDS_LIB standard
J 0
(-6625 2275);
DISPLAY INVISIBLE (-6625 2275);
FORCEPROP 1 LAST BODY_TYPE PLUMBING
J 0
(-6625 2225);
DISPLAY 0.574468 (-6625 2225);
PAINT GREEN (-6625 2225);
DISPLAY INVISIBLE (-6625 2225);
FORCEPROP 1 LAST HDL_TAP TRUE
J 0
(-6300 2150);
DISPLAY 0.574468 (-6300 2150);
PAINT GREEN (-6300 2150);
DISPLAY INVISIBLE (-6300 2150);
FORCEPROP 1 LAST PATH I457
J 0
(-6627 2275);
DISPLAY 0.872340 (-6627 2275);
PAINT GREEN (-6627 2275);
DISPLAY INVISIBLE (-6627 2275);
FORCEADD TAP..6
(-6625 2175);
FORCEPROP 3 LASTPIN (-6575 2175) SIG_NAME GMI_CPU0_G1_CPU1_G3_TX_DN<6>
J 0
(-6565 2185);
DISPLAY 0.659574 (-6565 2185);
PAINT MONO (-6565 2185);
DISPLAY INVISIBLE (-6565 2185);
FORCEPROP 1 LASTPIN (-6575 2175) BN 6
J 0
(-6627 2183);
DISPLAY 0.489362 (-6627 2183);
PAINT MONO (-6627 2183);
FORCEPROP 2 LAST CDS_LIB standard
J 0
(-6625 2175);
DISPLAY INVISIBLE (-6625 2175);
FORCEPROP 1 LAST BODY_TYPE PLUMBING
J 0
(-6625 2125);
DISPLAY 0.574468 (-6625 2125);
PAINT GREEN (-6625 2125);
DISPLAY INVISIBLE (-6625 2125);
FORCEPROP 1 LAST HDL_TAP TRUE
J 0
(-6300 2050);
DISPLAY 0.574468 (-6300 2050);
PAINT GREEN (-6300 2050);
DISPLAY INVISIBLE (-6300 2050);
FORCEPROP 1 LAST PATH I458
J 0
(-6627 2175);
DISPLAY 0.872340 (-6627 2175);
PAINT GREEN (-6627 2175);
DISPLAY INVISIBLE (-6627 2175);
FORCEADD TAP..6
(-6625 1975);
FORCEPROP 3 LASTPIN (-6575 1975) SIG_NAME GMI_CPU0_G1_CPU1_G3_TX_DN<4>
J 0
(-6565 1985);
DISPLAY 0.659574 (-6565 1985);
PAINT MONO (-6565 1985);
DISPLAY INVISIBLE (-6565 1985);
FORCEPROP 1 LASTPIN (-6575 1975) BN 4
J 0
(-6627 1983);
DISPLAY 0.489362 (-6627 1983);
PAINT MONO (-6627 1983);
FORCEPROP 2 LAST CDS_LIB standard
J 0
(-6625 1975);
DISPLAY INVISIBLE (-6625 1975);
FORCEPROP 1 LAST BODY_TYPE PLUMBING
J 0
(-6625 1925);
DISPLAY 0.574468 (-6625 1925);
PAINT GREEN (-6625 1925);
DISPLAY INVISIBLE (-6625 1925);
FORCEPROP 1 LAST HDL_TAP TRUE
J 0
(-6300 1850);
DISPLAY 0.574468 (-6300 1850);
PAINT GREEN (-6300 1850);
DISPLAY INVISIBLE (-6300 1850);
FORCEPROP 1 LAST PATH I459
J 0
(-6627 1975);
DISPLAY 0.872340 (-6627 1975);
PAINT GREEN (-6627 1975);
DISPLAY INVISIBLE (-6627 1975);
FORCEADD TAP..6
(-6625 2075);
FORCEPROP 3 LASTPIN (-6575 2075) SIG_NAME GMI_CPU0_G1_CPU1_G3_TX_DN<5>
J 0
(-6565 2085);
DISPLAY 0.659574 (-6565 2085);
PAINT MONO (-6565 2085);
DISPLAY INVISIBLE (-6565 2085);
FORCEPROP 1 LASTPIN (-6575 2075) BN 5
J 0
(-6627 2083);
DISPLAY 0.489362 (-6627 2083);
PAINT MONO (-6627 2083);
FORCEPROP 2 LAST CDS_LIB standard
J 0
(-6625 2075);
DISPLAY INVISIBLE (-6625 2075);
FORCEPROP 1 LAST BODY_TYPE PLUMBING
J 0
(-6625 2025);
DISPLAY 0.574468 (-6625 2025);
PAINT GREEN (-6625 2025);
DISPLAY INVISIBLE (-6625 2025);
FORCEPROP 1 LAST HDL_TAP TRUE
J 0
(-6300 1950);
DISPLAY 0.574468 (-6300 1950);
PAINT GREEN (-6300 1950);
DISPLAY INVISIBLE (-6300 1950);
FORCEPROP 1 LAST PATH I460
J 0
(-6627 2075);
DISPLAY 0.872340 (-6627 2075);
PAINT GREEN (-6627 2075);
DISPLAY INVISIBLE (-6627 2075);
FORCEADD TAP..6
(-6625 1875);
FORCEPROP 3 LASTPIN (-6575 1875) SIG_NAME GMI_CPU0_G1_CPU1_G3_TX_DN<3>
J 0
(-6565 1885);
DISPLAY 0.659574 (-6565 1885);
PAINT MONO (-6565 1885);
DISPLAY INVISIBLE (-6565 1885);
FORCEPROP 1 LASTPIN (-6575 1875) BN 3
J 0
(-6627 1883);
DISPLAY 0.489362 (-6627 1883);
PAINT MONO (-6627 1883);
FORCEPROP 2 LAST CDS_LIB standard
J 0
(-6625 1875);
DISPLAY INVISIBLE (-6625 1875);
FORCEPROP 1 LAST BODY_TYPE PLUMBING
J 0
(-6625 1825);
DISPLAY 0.574468 (-6625 1825);
PAINT GREEN (-6625 1825);
DISPLAY INVISIBLE (-6625 1825);
FORCEPROP 1 LAST HDL_TAP TRUE
J 0
(-6300 1750);
DISPLAY 0.574468 (-6300 1750);
PAINT GREEN (-6300 1750);
DISPLAY INVISIBLE (-6300 1750);
FORCEPROP 1 LAST PATH I461
J 0
(-6627 1875);
DISPLAY 0.872340 (-6627 1875);
PAINT GREEN (-6627 1875);
DISPLAY INVISIBLE (-6627 1875);
FORCEADD TAP..6
(-6625 1775);
FORCEPROP 3 LASTPIN (-6575 1775) SIG_NAME GMI_CPU0_G1_CPU1_G3_TX_DN<2>
J 0
(-6565 1785);
DISPLAY 0.659574 (-6565 1785);
PAINT MONO (-6565 1785);
DISPLAY INVISIBLE (-6565 1785);
FORCEPROP 1 LASTPIN (-6575 1775) BN 2
J 0
(-6627 1783);
DISPLAY 0.489362 (-6627 1783);
PAINT MONO (-6627 1783);
FORCEPROP 2 LAST CDS_LIB standard
J 0
(-6625 1775);
DISPLAY INVISIBLE (-6625 1775);
FORCEPROP 1 LAST BODY_TYPE PLUMBING
J 0
(-6625 1725);
DISPLAY 0.574468 (-6625 1725);
PAINT GREEN (-6625 1725);
DISPLAY INVISIBLE (-6625 1725);
FORCEPROP 1 LAST HDL_TAP TRUE
J 0
(-6300 1650);
DISPLAY 0.574468 (-6300 1650);
PAINT GREEN (-6300 1650);
DISPLAY INVISIBLE (-6300 1650);
FORCEPROP 1 LAST PATH I462
J 0
(-6627 1775);
DISPLAY 0.872340 (-6627 1775);
PAINT GREEN (-6627 1775);
DISPLAY INVISIBLE (-6627 1775);
FORCEADD TAP..6
(-6625 1575);
FORCEPROP 3 LASTPIN (-6575 1575) SIG_NAME GMI_CPU0_G1_CPU1_G3_TX_DN<0>
J 0
(-6565 1585);
DISPLAY 0.659574 (-6565 1585);
PAINT MONO (-6565 1585);
DISPLAY INVISIBLE (-6565 1585);
FORCEPROP 1 LASTPIN (-6575 1575) BN 0
J 0
(-6627 1583);
DISPLAY 0.489362 (-6627 1583);
PAINT MONO (-6627 1583);
FORCEPROP 2 LAST CDS_LIB standard
J 0
(-6625 1575);
DISPLAY INVISIBLE (-6625 1575);
FORCEPROP 1 LAST BODY_TYPE PLUMBING
J 0
(-6625 1525);
DISPLAY 0.574468 (-6625 1525);
PAINT GREEN (-6625 1525);
DISPLAY INVISIBLE (-6625 1525);
FORCEPROP 1 LAST HDL_TAP TRUE
J 0
(-6300 1450);
DISPLAY 0.574468 (-6300 1450);
PAINT GREEN (-6300 1450);
DISPLAY INVISIBLE (-6300 1450);
FORCEPROP 1 LAST PATH I463
J 0
(-6627 1575);
DISPLAY 0.872340 (-6627 1575);
PAINT GREEN (-6627 1575);
DISPLAY INVISIBLE (-6627 1575);
FORCEADD TAP..6
(-6625 1675);
FORCEPROP 3 LASTPIN (-6575 1675) SIG_NAME GMI_CPU0_G1_CPU1_G3_TX_DN<1>
J 0
(-6565 1685);
DISPLAY 0.659574 (-6565 1685);
PAINT MONO (-6565 1685);
DISPLAY INVISIBLE (-6565 1685);
FORCEPROP 1 LASTPIN (-6575 1675) BN 1
J 0
(-6627 1683);
DISPLAY 0.489362 (-6627 1683);
PAINT MONO (-6627 1683);
FORCEPROP 2 LAST CDS_LIB standard
J 0
(-6625 1675);
DISPLAY INVISIBLE (-6625 1675);
FORCEPROP 1 LAST BODY_TYPE PLUMBING
J 0
(-6625 1625);
DISPLAY 0.574468 (-6625 1625);
PAINT GREEN (-6625 1625);
DISPLAY INVISIBLE (-6625 1625);
FORCEPROP 1 LAST HDL_TAP TRUE
J 0
(-6300 1550);
DISPLAY 0.574468 (-6300 1550);
PAINT GREEN (-6300 1550);
DISPLAY INVISIBLE (-6300 1550);
FORCEPROP 1 LAST PATH I464
J 0
(-6627 1675);
DISPLAY 0.872340 (-6627 1675);
PAINT GREEN (-6627 1675);
DISPLAY INVISIBLE (-6627 1675);
FORCEADD OFFPAGE..1
(-7575 3300);
FORCEPROP 2 LASTPIN (-7525 3300) SIG_NAME GMI_CPU0_G1_CPU1_G3_TX_DN<15:0>
J 0
(-7535 3310);
DISPLAY 0.489362 (-7535 3310);
FORCEPROP 2 LAST $XR0 22 
J 0
(-7826 3300);
DISPLAY 0.638298 (-7826 3300);
PAINT MONO (-7826 3300);
FORCEPROP 2 LAST CDS_LIB standard
J 0
(-7575 3300);
DISPLAY INVISIBLE (-7575 3300);
FORCEPROP 1 LAST OFFPAGE TRUE
J 0
(-7250 3175);
DISPLAY 0.872340 (-7250 3175);
PAINT GREEN (-7250 3175);
DISPLAY INVISIBLE (-7250 3175);
FORCEPROP 1 LAST COMMENT_BODY TRUE
J 0
(-7450 3200);
DISPLAY 0.872340 (-7450 3200);
PAINT GREEN (-7450 3200);
DISPLAY INVISIBLE (-7450 3200);
FORCEPROP 2 LAST PATH I465
J 0
(-7825 3350);
DISPLAY 1.021277 (-7825 3350);
DISPLAY INVISIBLE (-7825 3350);
FORCEADD QUANTA_TITLE_BLOCK_C..1
(-100 100);
FORCEPROP 0 LAST CDS_CON_LAST_MODIFIED Fri Mar 11 14:52:36 2022
J 0
(-1985 115);
DISPLAY INVISIBLE (-1985 115);
FORCEPROP 1 LAST CUSTOM_TXT_CDS <CON_LAST_MODIFIED>
J 0
(-1985 115);
DISPLAY 0.978723 (-1985 115);
FORCEPROP 2 LAST CUSTOM_TXT_CDS <XR_PAGE_TITLE>
J 0
(-7990 5350);
DISPLAY 0.638298 (-7990 5350);
PAINT PINK (-7990 5350);
DISPLAY INVISIBLE (-7990 5350);
FORCEPROP 1 LAST CUSTOM_TXT_CDS <NAME_2>
J 0
(-3275 150);
FORCEPROP 1 LAST CUSTOM_TXT_CDS <NAME_1>
J 0
(-3275 275);
FORCEPROP 1 LAST CUSTOM_TXT_CDS <Q_NUMBER>
J 0
(-1503 203);
DISPLAY 1.212766 (-1503 203);
FORCEPROP 1 LAST CUSTOM_TXT_CDS <Q_PROJ>
J 0
(-2482 202);
DISPLAY 1.212766 (-2482 202);
FORCEPROP 1 LAST CUSTOM_TXT_CDS <Q_REV>
J 0
(-284 203);
DISPLAY 1.212766 (-284 203);
FORCEPROP 1 LAST CUSTOM_TXT_CDS <CON_PAGE_NUM> OF <CON_TOTAL_PAGES>
J 0
(-546 118);
DISPLAY 0.978723 (-546 118);
FORCEPROP 1 LAST Q_DEPT BU9
J 1
(-3863 149);
DISPLAY 1.957447 (-3863 149);
PAINT GREEN (-3863 149);
FORCEPROP 1 LAST Q_TITLE CPU1 PCIE G2/G3
J 0
(-9466 126);
DISPLAY 2.446809 (-9466 126);
PAINT GREEN (-9466 126);
FORCEPROP 2 LAST PAGE_BORDER TRUE
J 0
(-7990 5350);
DISPLAY 0.638298 (-7990 5350);
PAINT PINK (-7990 5350);
DISPLAY INVISIBLE (-7990 5350);
FORCEPROP 1 LAST CDS_LMAN_SYM_OUTLINE -9475,6775,100,-125
J 0
(-100 100);
DISPLAY 0.468085 (-100 100);
PAINT GREEN (-100 100);
DISPLAY INVISIBLE (-100 100);
FORCEPROP 2 LAST CDS_LIB pure_quanta
J 0
(-100 100);
DISPLAY INVISIBLE (-100 100);
FORCEPROP 1 LAST COMMENT_BODY TRUE
J 0
(-88 87);
DISPLAY 0.978723 (-88 87);
PAINT GREEN (-88 87);
DISPLAY INVISIBLE (-88 87);
FORCEPROP 2 LAST CDS_XR_PAGE_TITLE CR-50 : @T6G_MB_LIB.T6G(SCH_1):PAGE50
J 0
(-7990 5350);
DISPLAY 0.638298 (-7990 5350);
PAINT PINK (-7990 5350);
DISPLAY INVISIBLE (-7990 5350);
WIRE 17 -1 (-2875 4975)(-2875 4875);
WIRE 17 -1 (-2875 5075)(-2875 4975);
WIRE 17 -1 (-2875 4875)(-2875 4775);
WIRE 17 -1 (-2875 4775)(-2875 4675);
WIRE 17 -1 (-2875 5175)(-2875 5075);
WIRE 17 -1 (-2875 5275)(-2875 5175);
WIRE 17 -1 (-2875 4675)(-2875 4575);
WIRE 17 -1 (-2875 4575)(-2875 4475);
WIRE 17 -1 (-2875 5375)(-2875 5275);
WIRE 17 -1 (-2875 5475)(-2875 5375);
WIRE 17 -1 (-2875 4475)(-2875 4375);
WIRE 17 -1 (-2875 4375)(-2875 4275);
WIRE 17 -1 (-2875 5575)(-2875 5475);
WIRE 17 -1 (-2875 5675)(-2875 5575);
WIRE 17 -1 (-2875 5775)(-2875 5675);
WIRE 17 -1 (-2875 5975)(-2875 5775);
WIRE 17 -1 (-2875 5975)(-1850 5975);
FORCEPROP 2 LAST SIG_NAME GMI_CPU1_G2_CPU0_G0_TX_DN<15:0>
J 0
(-2835 5985);
DISPLAY 0.489362 (-2835 5985);
WIRE 17 -1 (-3025 5725)(-3025 5625);
WIRE 17 -1 (-3025 5825)(-3025 5725);
WIRE 17 -1 (-3025 5625)(-3025 5525);
WIRE 17 -1 (-3025 5525)(-3025 5425);
WIRE 17 -1 (-3025 6025)(-3025 5825);
WIRE 17 -1 (-3025 6025)(-1850 6025);
FORCEPROP 2 LAST SIG_NAME GMI_CPU1_G2_CPU0_G0_TX_DP<15:0>
J 0
(-2835 6035);
DISPLAY 0.489362 (-2835 6035);
WIRE 17 -1 (-3025 5425)(-3025 5325);
WIRE 17 -1 (-3025 5325)(-3025 5225);
WIRE 17 -1 (-3025 5225)(-3025 5125);
WIRE 17 -1 (-3025 5125)(-3025 5025);
WIRE 17 -1 (-3025 5025)(-3025 4925);
WIRE 17 -1 (-3025 4925)(-3025 4825);
WIRE 17 -1 (-3025 4825)(-3025 4725);
WIRE 17 -1 (-3025 4725)(-3025 4625);
WIRE 17 -1 (-3025 4625)(-3025 4525);
WIRE 17 -1 (-3025 4525)(-3025 4425);
WIRE 17 -1 (-3025 4425)(-3025 4325);
WIRE 17 -1 (-2850 2900)(-2850 2800);
WIRE 17 -1 (-2850 3000)(-2850 2900);
WIRE 17 -1 (-2850 2800)(-2850 2700);
WIRE 17 -1 (-2850 2700)(-2850 2600);
WIRE 17 -1 (-2850 3100)(-2850 3000);
WIRE 17 -1 (-2850 3300)(-2850 3100);
WIRE 17 -1 (-2850 2600)(-2850 2500);
WIRE 17 -1 (-2850 2500)(-2850 2400);
WIRE 17 -1 (-2850 3300)(-1825 3300);
FORCEPROP 2 LAST SIG_NAME GMI_CPU1_G3_CPU0_G1_TX_DN<15:0>
J 0
(-2760 3310);
DISPLAY 0.489362 (-2760 3310);
WIRE 17 -1 (-2850 2400)(-2850 2300);
WIRE 17 -1 (-2850 2300)(-2850 2200);
WIRE 17 -1 (-2850 2200)(-2850 2100);
WIRE 17 -1 (-2850 2100)(-2850 2000);
WIRE 17 -1 (-2850 2000)(-2850 1900);
WIRE 17 -1 (-2850 1900)(-2850 1800);
WIRE 17 -1 (-2850 1800)(-2850 1700);
WIRE 17 -1 (-2850 1700)(-2850 1600);
WIRE 17 -1 (-3000 3350)(-3000 3150);
WIRE 17 -1 (-3000 3350)(-1825 3350);
FORCEPROP 2 LAST SIG_NAME GMI_CPU1_G3_CPU0_G1_TX_DP<15:0>
J 0
(-2760 3360);
DISPLAY 0.489362 (-2760 3360);
WIRE 17 -1 (-3000 2850)(-3000 2750);
WIRE 17 -1 (-3000 2950)(-3000 2850);
WIRE 17 -1 (-3000 2750)(-3000 2650);
WIRE 17 -1 (-3000 2650)(-3000 2550);
WIRE 17 -1 (-3000 3050)(-3000 2950);
WIRE 17 -1 (-3000 3150)(-3000 3050);
WIRE 17 -1 (-3000 2550)(-3000 2450);
WIRE 17 -1 (-3000 2450)(-3000 2350);
WIRE 17 -1 (-3000 2350)(-3000 2250);
WIRE 17 -1 (-3000 2250)(-3000 2150);
WIRE 17 -1 (-3000 2150)(-3000 2050);
WIRE 17 -1 (-3000 2050)(-3000 1950);
WIRE 17 -1 (-3000 1950)(-3000 1850);
WIRE 17 -1 (-3000 1850)(-3000 1750);
WIRE 17 -1 (-3000 1750)(-3000 1650);
WIRE 17 -1 (-6550 5025)(-6550 5125);
WIRE 17 -1 (-6550 4925)(-6550 5025);
WIRE 17 -1 (-6550 5125)(-6550 5225);
WIRE 17 -1 (-6550 5225)(-6550 5325);
WIRE 17 -1 (-6550 4825)(-6550 4925);
WIRE 17 -1 (-6550 4725)(-6550 4825);
WIRE 17 -1 (-6550 5325)(-6550 5425);
WIRE 17 -1 (-6550 5425)(-6550 5525);
WIRE 17 -1 (-6550 4625)(-6550 4725);
WIRE 17 -1 (-6550 4525)(-6550 4625);
WIRE 17 -1 (-6550 5525)(-6550 5625);
WIRE 17 -1 (-6550 5625)(-6550 5725);
WIRE 17 -1 (-6550 4425)(-6550 4525);
WIRE 17 -1 (-6550 4325)(-6550 4425);
WIRE 17 -1 (-6550 5725)(-6550 5825);
WIRE 17 -1 (-6550 5825)(-6550 6025);
WIRE 17 -1 (-6550 6025)(-7650 6025);
FORCEPROP 2 LAST SIG_NAME GMI_CPU0_G0_CPU1_G2_TX_DP<15:0>
J 0
(-7610 6035);
DISPLAY 0.489362 (-7610 6035);
WIRE 17 -1 (-6700 4975)(-6700 5075);
WIRE 17 -1 (-6700 4875)(-6700 4975);
WIRE 17 -1 (-6700 5075)(-6700 5175);
WIRE 17 -1 (-6700 5175)(-6700 5275);
WIRE 17 -1 (-6700 4775)(-6700 4875);
WIRE 17 -1 (-6700 4675)(-6700 4775);
WIRE 17 -1 (-6700 5275)(-6700 5375);
WIRE 17 -1 (-6700 5375)(-6700 5475);
WIRE 17 -1 (-6700 4575)(-6700 4675);
WIRE 17 -1 (-6700 4475)(-6700 4575);
WIRE 17 -1 (-6700 5475)(-6700 5575);
WIRE 17 -1 (-6700 5575)(-6700 5675);
WIRE 17 -1 (-6700 4375)(-6700 4475);
WIRE 17 -1 (-6700 4275)(-6700 4375);
WIRE 17 -1 (-6700 5675)(-6700 5775);
WIRE 17 -1 (-6700 5775)(-6700 5975);
WIRE 17 -1 (-6700 5975)(-7650 5975);
FORCEPROP 2 LAST SIG_NAME GMI_CPU0_G0_CPU1_G2_TX_DN<15:0>
J 0
(-7610 5985);
DISPLAY 0.489362 (-7610 5985);
WIRE 17 -1 (-6675 2600)(-6675 2500);
WIRE 17 -1 (-6675 2700)(-6675 2600);
WIRE 17 -1 (-6675 2500)(-6675 2400);
WIRE 17 -1 (-6675 2400)(-6675 2300);
WIRE 17 -1 (-6675 2800)(-6675 2700);
WIRE 17 -1 (-6675 2900)(-6675 2800);
WIRE 17 -1 (-6675 2300)(-6675 2200);
WIRE 17 -1 (-6675 2200)(-6675 2100);
WIRE 17 -1 (-6675 3000)(-6675 2900);
WIRE 17 -1 (-6675 3100)(-6675 3000);
WIRE 17 -1 (-6675 2100)(-6675 2000);
WIRE 17 -1 (-6675 2000)(-6675 1900);
WIRE 17 -1 (-6675 3300)(-6675 3100);
WIRE 17 -1 (-6675 3300)(-7525 3300);
WIRE 17 -1 (-6675 1900)(-6675 1800);
WIRE 17 -1 (-6675 1800)(-6675 1700);
WIRE 17 -1 (-6525 1950)(-6525 1850);
WIRE 17 -1 (-6525 2050)(-6525 1950);
WIRE 17 -1 (-6525 1850)(-6525 1750);
WIRE 17 -1 (-6525 1750)(-6525 1650);
WIRE 17 -1 (-6525 2150)(-6525 2050);
WIRE 17 -1 (-6525 2250)(-6525 2150);
WIRE 17 -1 (-6525 2350)(-6525 2250);
WIRE 17 -1 (-6525 2450)(-6525 2350);
WIRE 17 -1 (-6525 2550)(-6525 2450);
WIRE 17 -1 (-6525 2650)(-6525 2550);
WIRE 17 -1 (-6525 2750)(-6525 2650);
WIRE 17 -1 (-6525 2850)(-6525 2750);
WIRE 17 -1 (-6525 2950)(-6525 2850);
WIRE 17 -1 (-6525 3050)(-6525 2950);
WIRE 17 -1 (-6525 3150)(-6525 3050);
WIRE 17 -1 (-6525 3350)(-6525 3150);
WIRE 17 -1 (-6525 3350)(-7525 3350);
WIRE 17 -1 (-6675 1700)(-6675 1600);
WIRE 16 -1 (-6575 2875)(-5975 2875);
WIRE 16 -1 (-6575 1875)(-5975 1875);
WIRE 16 -1 (-6575 1575)(-5975 1575);
WIRE 16 -1 (-6575 2175)(-5975 2175);
WIRE 16 -1 (-6425 2925)(-5975 2925);
WIRE 16 -1 (-6425 2625)(-5975 2625);
WIRE 16 -1 (-6425 1725)(-5975 1725);
WIRE 16 -1 (-6425 2025)(-5975 2025);
WIRE 16 -1 (-6575 2975)(-5975 2975);
WIRE 16 -1 (-6575 2675)(-5975 2675);
WIRE 16 -1 (-6575 2375)(-5975 2375);
WIRE 16 -1 (-6425 2225)(-5975 2225);
WIRE 16 -1 (-6575 1975)(-5975 1975);
WIRE 16 -1 (-6575 1675)(-5975 1675);
WIRE 16 -1 (-6425 2425)(-5975 2425);
WIRE 16 -1 (-6575 2275)(-5975 2275);
WIRE 16 -1 (-6425 3025)(-5975 3025);
WIRE 16 -1 (-6425 2725)(-5975 2725);
WIRE 16 -1 (-6425 2125)(-5975 2125);
WIRE 16 -1 (-6425 1825)(-5975 1825);
WIRE 16 -1 (-6575 2475)(-5975 2475);
WIRE 16 -1 (-6575 3075)(-5975 3075);
WIRE 16 -1 (-6575 2775)(-5975 2775);
WIRE 16 -1 (-6425 2325)(-5975 2325);
WIRE 16 -1 (-6575 1775)(-5975 1775);
WIRE 16 -1 (-6575 2075)(-5975 2075);
WIRE 16 -1 (-6425 2825)(-5975 2825);
WIRE 16 -1 (-6425 2525)(-5975 2525);
WIRE 16 -1 (-6425 1625)(-5975 1625);
WIRE 16 -1 (-6425 3125)(-5975 3125);
WIRE 16 -1 (-6425 1925)(-5975 1925);
WIRE 16 -1 (-6575 2575)(-5975 2575);
WIRE 16 -1 (-6600 5050)(-6000 5050);
WIRE 16 -1 (-6600 5150)(-6000 5150);
WIRE 16 -1 (-6600 5250)(-6000 5250);
WIRE 16 -1 (-6450 5100)(-6000 5100);
WIRE 16 -1 (-6600 5350)(-6000 5350);
WIRE 16 -1 (-6450 5200)(-6000 5200);
WIRE 16 -1 (-6600 5450)(-6000 5450);
WIRE 16 -1 (-6450 5300)(-6000 5300);
WIRE 16 -1 (-6600 5550)(-6000 5550);
WIRE 16 -1 (-6450 5400)(-6000 5400);
WIRE 16 -1 (-6600 5650)(-6000 5650);
WIRE 16 -1 (-6450 5500)(-6000 5500);
WIRE 16 -1 (-6600 5750)(-6000 5750);
WIRE 16 -1 (-6450 5600)(-6000 5600);
WIRE 16 -1 (-6450 5700)(-6000 5700);
WIRE 16 -1 (-6450 5800)(-6000 5800);
WIRE 16 -1 (-6600 4250)(-6000 4250);
WIRE 16 -1 (-6450 4300)(-6000 4300);
WIRE 16 -1 (-6600 4450)(-6000 4450);
WIRE 16 -1 (-6450 4500)(-6000 4500);
WIRE 16 -1 (-6600 4650)(-6000 4650);
WIRE 16 -1 (-6450 4700)(-6000 4700);
WIRE 16 -1 (-6600 4850)(-6000 4850);
WIRE 16 -1 (-6450 4900)(-6000 4900);
WIRE 16 -1 (-6600 4350)(-6000 4350);
WIRE 16 -1 (-6450 4400)(-6000 4400);
WIRE 16 -1 (-6600 4550)(-6000 4550);
WIRE 16 -1 (-6450 4600)(-6000 4600);
WIRE 16 -1 (-6600 4750)(-6000 4750);
WIRE 16 -1 (-6450 4800)(-6000 4800);
WIRE 16 -1 (-6600 4950)(-6000 4950);
WIRE 16 -1 (-6450 5000)(-6000 5000);
WIRE 16 -1 (-3475 1625)(-3100 1625);
WIRE 16 -1 (-3475 1925)(-3100 1925);
WIRE 16 -1 (-3475 1725)(-3100 1725);
WIRE 16 -1 (-3475 2025)(-3100 2025);
WIRE 16 -1 (-3475 1825)(-3100 1825);
WIRE 16 -1 (-3475 1775)(-2950 1775);
WIRE 16 -1 (-3475 1875)(-2950 1875);
WIRE 16 -1 (-3475 1575)(-2950 1575);
WIRE 16 -1 (-3475 1975)(-2950 1975);
WIRE 16 -1 (-3475 1675)(-2950 1675);
WIRE 16 -1 (-3475 2225)(-3100 2225);
WIRE 16 -1 (-3475 2425)(-3100 2425);
WIRE 16 -1 (-3475 2325)(-3100 2325);
WIRE 16 -1 (-3475 2525)(-3100 2525);
WIRE 16 -1 (-3475 2125)(-3100 2125);
WIRE 16 -1 (-3475 2625)(-3100 2625);
WIRE 16 -1 (-3475 2925)(-3100 2925);
WIRE 16 -1 (-3475 3025)(-3100 3025);
WIRE 16 -1 (-3475 2725)(-3100 2725);
WIRE 16 -1 (-3475 2825)(-3100 2825);
WIRE 16 -1 (-3475 3125)(-3100 3125);
WIRE 16 -1 (-3475 2175)(-2950 2175);
WIRE 16 -1 (-3475 2675)(-2950 2675);
WIRE 16 -1 (-3475 2375)(-2950 2375);
WIRE 16 -1 (-3475 2075)(-2950 2075);
WIRE 16 -1 (-3475 2975)(-2950 2975);
WIRE 16 -1 (-3475 2275)(-2950 2275);
WIRE 16 -1 (-3475 2775)(-2950 2775);
WIRE 16 -1 (-3475 2475)(-2950 2475);
WIRE 16 -1 (-3475 3075)(-2950 3075);
WIRE 16 -1 (-3475 2575)(-2950 2575);
WIRE 16 -1 (-3475 2875)(-2950 2875);
WIRE 16 -1 (-3500 4300)(-3125 4300);
WIRE 16 -1 (-3500 4500)(-3125 4500);
WIRE 16 -1 (-3500 4400)(-3125 4400);
WIRE 16 -1 (-3500 4600)(-3125 4600);
WIRE 16 -1 (-3500 5100)(-3125 5100);
WIRE 16 -1 (-3500 4700)(-3125 4700);
WIRE 16 -1 (-3500 4900)(-3125 4900);
WIRE 16 -1 (-3500 4800)(-3125 4800);
WIRE 16 -1 (-3500 5000)(-3125 5000);
WIRE 16 -1 (-3500 5200)(-3125 5200);
WIRE 16 -1 (-3500 5300)(-3125 5300);
WIRE 16 -1 (-3500 5400)(-3125 5400);
WIRE 16 -1 (-3500 5500)(-3125 5500);
WIRE 16 -1 (-3500 5600)(-3125 5600);
WIRE 16 -1 (-3500 5800)(-3125 5800);
WIRE 16 -1 (-3500 5700)(-3125 5700);
WIRE 16 -1 (-3500 5050)(-2975 5050);
WIRE 16 -1 (-3500 5150)(-2975 5150);
WIRE 16 -1 (-3500 5250)(-2975 5250);
WIRE 16 -1 (-3500 5350)(-2975 5350);
WIRE 16 -1 (-3500 5450)(-2975 5450);
WIRE 16 -1 (-3500 5550)(-2975 5550);
WIRE 16 -1 (-3500 5650)(-2975 5650);
WIRE 16 -1 (-3500 5750)(-2975 5750);
WIRE 16 -1 (-3500 4250)(-2975 4250);
WIRE 16 -1 (-3500 4450)(-2975 4450);
WIRE 16 -1 (-3500 4650)(-2975 4650);
WIRE 16 -1 (-3500 4850)(-2975 4850);
WIRE 16 -1 (-3500 4350)(-2975 4350);
WIRE 16 -1 (-3500 4550)(-2975 4550);
WIRE 16 -1 (-3500 4750)(-2975 4750);
WIRE 16 -1 (-3500 4950)(-2975 4950);
FORCENOTE
LANE REVERSAL
(-1925 2025) 0;
DISPLAY LEFT (-1925 2025);
DISPLAY 1.595745 (-1925 2025);
FORCENOTE
LANE REVERSAL
(-1900 4750) 0;
DISPLAY LEFT (-1900 4750);
DISPLAY 1.595745 (-1900 4750);
QUIT
